FILE_TYPE = MACRO_DRAWING;
SET COLOR_WIRE YELLOW;
SET COLOR_PROP ORANGE;
SET COLOR_DOT WHITE;
SET COLOR_ARC YELLOW;
SET COLOR_BODY GREEN;
SET COLOR_NOTE PURPLE;
SET PROP_DISPLAY VALUE;
SET PAGE_NUMBER P52;
FORCEADD GENOA_SP5..18
(-4625 2350);
FORCEPROP 1 LAST LOCATION U26
J 0
(-5225 3550);
DISPLAY 0.489362 (-5225 3550);
PAINT SKYBLUE (-5225 3550);
FORCEPROP 0 LAST $SEC 18
J 0
(-5200 3650);
DISPLAY 0.680851 (-5200 3650);
PAINT MONO (-5200 3650);
DISPLAY INVISIBLE (-5200 3650);
FORCEPROP 0 LAST CDS_SEC 18
J 0
(-5225 3550);
DISPLAY 1.021277 (-5225 3550);
DISPLAY INVISIBLE (-5225 3550);
FORCEPROP 0 LASTPIN (-5375 3100) $PN CV36
J 2
(-5385 3110);
DISPLAY 0.489362 (-5385 3110);
PAINT MONO (-5385 3110);
FORCEPROP 0 LASTPIN (-5375 3000) $PN CY36
J 2
(-5385 3010);
DISPLAY 0.489362 (-5385 3010);
PAINT MONO (-5385 3010);
FORCEPROP 0 LASTPIN (-5375 2900) $PN DB36
J 2
(-5385 2910);
DISPLAY 0.489362 (-5385 2910);
PAINT MONO (-5385 2910);
FORCEPROP 0 LASTPIN (-5375 2800) $PN CW33
J 2
(-5385 2810);
DISPLAY 0.489362 (-5385 2810);
PAINT MONO (-5385 2810);
FORCEPROP 0 LASTPIN (-5375 2700) $PN DC33
J 2
(-5385 2710);
DISPLAY 0.489362 (-5385 2710);
PAINT MONO (-5385 2710);
FORCEPROP 0 LASTPIN (-5375 2600) $PN DA33
J 2
(-5385 2610);
DISPLAY 0.489362 (-5385 2610);
PAINT MONO (-5385 2610);
FORCEPROP 0 LASTPIN (-5375 2500) $PN CW30
J 2
(-5385 2510);
DISPLAY 0.489362 (-5385 2510);
PAINT MONO (-5385 2510);
FORCEPROP 0 LASTPIN (-5375 2400) $PN DC30
J 2
(-5385 2410);
DISPLAY 0.489362 (-5385 2410);
PAINT MONO (-5385 2410);
FORCEPROP 0 LASTPIN (-5375 2300) $PN DA30
J 2
(-5385 2310);
DISPLAY 0.489362 (-5385 2310);
PAINT MONO (-5385 2310);
FORCEPROP 0 LASTPIN (-5375 2200) $PN CW27
J 2
(-5385 2210);
DISPLAY 0.489362 (-5385 2210);
PAINT MONO (-5385 2210);
FORCEPROP 0 LASTPIN (-5375 2100) $PN DC27
J 2
(-5385 2110);
DISPLAY 0.489362 (-5385 2110);
PAINT MONO (-5385 2110);
FORCEPROP 0 LASTPIN (-5375 2000) $PN DA27
J 2
(-5385 2010);
DISPLAY 0.489362 (-5385 2010);
PAINT MONO (-5385 2010);
FORCEPROP 0 LASTPIN (-5375 1900) $PN CW24
J 2
(-5385 1910);
DISPLAY 0.489362 (-5385 1910);
PAINT MONO (-5385 1910);
FORCEPROP 0 LASTPIN (-5375 1800) $PN DC24
J 2
(-5385 1810);
DISPLAY 0.489362 (-5385 1810);
PAINT MONO (-5385 1810);
FORCEPROP 0 LASTPIN (-5375 1700) $PN DA24
J 2
(-5385 1710);
DISPLAY 0.489362 (-5385 1710);
PAINT MONO (-5385 1710);
FORCEPROP 0 LASTPIN (-5375 1600) $PN CU24
J 2
(-5385 1610);
DISPLAY 0.489362 (-5385 1610);
PAINT MONO (-5385 1610);
FORCEPROP 0 LASTPIN (-5375 3150) $PN CV35
J 2
(-5385 3160);
DISPLAY 0.489362 (-5385 3160);
PAINT MONO (-5385 3160);
FORCEPROP 0 LASTPIN (-5375 3050) $PN CY35
J 2
(-5385 3060);
DISPLAY 0.489362 (-5385 3060);
PAINT MONO (-5385 3060);
FORCEPROP 0 LASTPIN (-5375 2950) $PN DB35
J 2
(-5385 2960);
DISPLAY 0.489362 (-5385 2960);
PAINT MONO (-5385 2960);
FORCEPROP 0 LASTPIN (-5375 2850) $PN CW32
J 2
(-5385 2860);
DISPLAY 0.489362 (-5385 2860);
PAINT MONO (-5385 2860);
FORCEPROP 0 LASTPIN (-5375 2750) $PN DC32
J 2
(-5385 2760);
DISPLAY 0.489362 (-5385 2760);
PAINT MONO (-5385 2760);
FORCEPROP 0 LASTPIN (-5375 2650) $PN DA32
J 2
(-5385 2660);
DISPLAY 0.489362 (-5385 2660);
PAINT MONO (-5385 2660);
FORCEPROP 0 LASTPIN (-5375 2550) $PN CW29
J 2
(-5385 2560);
DISPLAY 0.489362 (-5385 2560);
PAINT MONO (-5385 2560);
FORCEPROP 0 LASTPIN (-5375 2450) $PN DC29
J 2
(-5385 2460);
DISPLAY 0.489362 (-5385 2460);
PAINT MONO (-5385 2460);
FORCEPROP 0 LASTPIN (-5375 2350) $PN DA29
J 2
(-5385 2360);
DISPLAY 0.489362 (-5385 2360);
PAINT MONO (-5385 2360);
FORCEPROP 0 LASTPIN (-5375 2250) $PN CW26
J 2
(-5385 2260);
DISPLAY 0.489362 (-5385 2260);
PAINT MONO (-5385 2260);
FORCEPROP 0 LASTPIN (-5375 2150) $PN DC26
J 2
(-5385 2160);
DISPLAY 0.489362 (-5385 2160);
PAINT MONO (-5385 2160);
FORCEPROP 0 LASTPIN (-5375 2050) $PN DA26
J 2
(-5385 2060);
DISPLAY 0.489362 (-5385 2060);
PAINT MONO (-5385 2060);
FORCEPROP 0 LASTPIN (-5375 1950) $PN CW23
J 2
(-5385 1960);
DISPLAY 0.489362 (-5385 1960);
PAINT MONO (-5385 1960);
FORCEPROP 0 LASTPIN (-5375 1850) $PN DC23
J 2
(-5385 1860);
DISPLAY 0.489362 (-5385 1860);
PAINT MONO (-5385 1860);
FORCEPROP 0 LASTPIN (-5375 1750) $PN DA23
J 2
(-5385 1760);
DISPLAY 0.489362 (-5385 1760);
PAINT MONO (-5385 1760);
FORCEPROP 0 LASTPIN (-5375 1650) $PN CU23
J 2
(-5385 1660);
DISPLAY 0.489362 (-5385 1660);
PAINT MONO (-5385 1660);
FORCEPROP 0 LASTPIN (-3875 3100) $PN CD35
J 0
(-3865 3110);
DISPLAY 0.489362 (-3865 3110);
PAINT MONO (-3865 3110);
FORCEPROP 0 LASTPIN (-3875 3000) $PN CF35
J 0
(-3865 3010);
DISPLAY 0.489362 (-3865 3010);
PAINT MONO (-3865 3010);
FORCEPROP 0 LASTPIN (-3875 2900) $PN CH35
J 0
(-3865 2910);
DISPLAY 0.489362 (-3865 2910);
PAINT MONO (-3865 2910);
FORCEPROP 0 LASTPIN (-3875 2800) $PN CC32
J 0
(-3865 2810);
DISPLAY 0.489362 (-3865 2810);
PAINT MONO (-3865 2810);
FORCEPROP 0 LASTPIN (-3875 2700) $PN CJ32
J 0
(-3865 2710);
DISPLAY 0.489362 (-3865 2710);
PAINT MONO (-3865 2710);
FORCEPROP 0 LASTPIN (-3875 2600) $PN CG32
J 0
(-3865 2610);
DISPLAY 0.489362 (-3865 2610);
PAINT MONO (-3865 2610);
FORCEPROP 0 LASTPIN (-3875 2500) $PN CE32
J 0
(-3865 2510);
DISPLAY 0.489362 (-3865 2510);
PAINT MONO (-3865 2510);
FORCEPROP 0 LASTPIN (-3875 2400) $PN CC29
J 0
(-3865 2410);
DISPLAY 0.489362 (-3865 2410);
PAINT MONO (-3865 2410);
FORCEPROP 0 LASTPIN (-3875 2300) $PN CG29
J 0
(-3865 2310);
DISPLAY 0.489362 (-3865 2310);
PAINT MONO (-3865 2310);
FORCEPROP 0 LASTPIN (-3875 2200) $PN CE29
J 0
(-3865 2210);
DISPLAY 0.489362 (-3865 2210);
PAINT MONO (-3865 2210);
FORCEPROP 0 LASTPIN (-3875 2100) $PN CC26
J 0
(-3865 2110);
DISPLAY 0.489362 (-3865 2110);
PAINT MONO (-3865 2110);
FORCEPROP 0 LASTPIN (-3875 2000) $PN CG26
J 0
(-3865 2010);
DISPLAY 0.489362 (-3865 2010);
PAINT MONO (-3865 2010);
FORCEPROP 0 LASTPIN (-3875 1900) $PN CE26
J 0
(-3865 1910);
DISPLAY 0.489362 (-3865 1910);
PAINT MONO (-3865 1910);
FORCEPROP 0 LASTPIN (-3875 1800) $PN CC23
J 0
(-3865 1810);
DISPLAY 0.489362 (-3865 1810);
PAINT MONO (-3865 1810);
FORCEPROP 0 LASTPIN (-3875 1700) $PN CG23
J 0
(-3865 1710);
DISPLAY 0.489362 (-3865 1710);
PAINT MONO (-3865 1710);
FORCEPROP 0 LASTPIN (-3875 1600) $PN CE23
J 0
(-3865 1610);
DISPLAY 0.489362 (-3865 1610);
PAINT MONO (-3865 1610);
FORCEPROP 0 LASTPIN (-3875 3150) $PN CD36
J 0
(-3865 3160);
DISPLAY 0.489362 (-3865 3160);
PAINT MONO (-3865 3160);
FORCEPROP 0 LASTPIN (-3875 3050) $PN CF36
J 0
(-3865 3060);
DISPLAY 0.489362 (-3865 3060);
PAINT MONO (-3865 3060);
FORCEPROP 0 LASTPIN (-3875 2950) $PN CH36
J 0
(-3865 2960);
DISPLAY 0.489362 (-3865 2960);
PAINT MONO (-3865 2960);
FORCEPROP 0 LASTPIN (-3875 2850) $PN CC33
J 0
(-3865 2860);
DISPLAY 0.489362 (-3865 2860);
PAINT MONO (-3865 2860);
FORCEPROP 0 LASTPIN (-3875 2750) $PN CJ33
J 0
(-3865 2760);
DISPLAY 0.489362 (-3865 2760);
PAINT MONO (-3865 2760);
FORCEPROP 0 LASTPIN (-3875 2650) $PN CG33
J 0
(-3865 2660);
DISPLAY 0.489362 (-3865 2660);
PAINT MONO (-3865 2660);
FORCEPROP 0 LASTPIN (-3875 2550) $PN CE33
J 0
(-3865 2560);
DISPLAY 0.489362 (-3865 2560);
PAINT MONO (-3865 2560);
FORCEPROP 0 LASTPIN (-3875 2450) $PN CC30
J 0
(-3865 2460);
DISPLAY 0.489362 (-3865 2460);
PAINT MONO (-3865 2460);
FORCEPROP 0 LASTPIN (-3875 2350) $PN CG30
J 0
(-3865 2360);
DISPLAY 0.489362 (-3865 2360);
PAINT MONO (-3865 2360);
FORCEPROP 0 LASTPIN (-3875 2250) $PN CE30
J 0
(-3865 2260);
DISPLAY 0.489362 (-3865 2260);
PAINT MONO (-3865 2260);
FORCEPROP 0 LASTPIN (-3875 2150) $PN CC27
J 0
(-3865 2160);
DISPLAY 0.489362 (-3865 2160);
PAINT MONO (-3865 2160);
FORCEPROP 0 LASTPIN (-3875 2050) $PN CG27
J 0
(-3865 2060);
DISPLAY 0.489362 (-3865 2060);
PAINT MONO (-3865 2060);
FORCEPROP 0 LASTPIN (-3875 1950) $PN CE27
J 0
(-3865 1960);
DISPLAY 0.489362 (-3865 1960);
PAINT MONO (-3865 1960);
FORCEPROP 0 LASTPIN (-3875 1850) $PN CC24
J 0
(-3865 1860);
DISPLAY 0.489362 (-3865 1860);
PAINT MONO (-3865 1860);
FORCEPROP 0 LASTPIN (-3875 1750) $PN CG24
J 0
(-3865 1760);
DISPLAY 0.489362 (-3865 1760);
PAINT MONO (-3865 1760);
FORCEPROP 0 LASTPIN (-3875 1650) $PN CE24
J 0
(-3865 1660);
DISPLAY 0.489362 (-3865 1660);
PAINT MONO (-3865 1660);
FORCEPROP 1 LAST MATERIAL IO
J 0
(-5220 3332);
DISPLAY 0.489362 (-5220 3332);
PAINT SKYBLUE (-5220 3332);
FORCEPROP 2 LAST VALUE SOCKET6096_13568-001
J 0
(-5225 3380);
DISPLAY 0.489362 (-5225 3380);
PAINT SKYBLUE (-5225 3380);
FORCEPROP 2 LAST PART_TYPE SMLF
J 0
(-5225 3475);
DISPLAY 1.021277 (-5225 3475);
FORCEPROP 2 LAST CDS_LIB pure_quanta
J 0
(-4625 2350);
DISPLAY INVISIBLE (-4625 2350);
FORCEPROP 1 LAST CDS_LMAN_SYM_OUTLINE -600,950,600,-950
J 0
(-4625 2350);
DISPLAY 0.468085 (-4625 2350);
PAINT GREEN (-4625 2350);
DISPLAY INVISIBLE (-4625 2350);
FORCEPROP 1 LAST NEEDS_NO_SIZE TRUE
J 0
(-4625 2350);
DISPLAY 0.723404 (-4625 2350);
PAINT GREEN (-4625 2350);
DISPLAY INVISIBLE (-4625 2350);
FORCEPROP 1 LAST PATH I147
J 0
(-4625 2350);
DISPLAY 0.723404 (-4625 2350);
PAINT GREEN (-4625 2350);
DISPLAY INVISIBLE (-4625 2350);
FORCEPROP 1 LAST PART_NUMBER DGA^6000030
J 0
(-5225 3425);
DISPLAY 0.489362 (-5225 3425);
PAINT SKYBLUE (-5225 3425);
DISPLAY INVISIBLE (-5225 3425);
FORCEADD GENOA_SP5..17
(-4625 4850);
FORCEPROP 1 LAST LOCATION U26
J 0
(-5225 6000);
DISPLAY 0.489362 (-5225 6000);
PAINT SKYBLUE (-5225 6000);
FORCEPROP 0 LAST $SEC 17
J 0
(-5200 6150);
DISPLAY 0.680851 (-5200 6150);
PAINT MONO (-5200 6150);
DISPLAY INVISIBLE (-5200 6150);
FORCEPROP 0 LAST CDS_SEC 17
J 0
(-5225 6025);
DISPLAY 1.021277 (-5225 6025);
DISPLAY INVISIBLE (-5225 6025);
FORCEPROP 0 LASTPIN (-5375 5600) $PN CM36
J 2
(-5385 5610);
DISPLAY 0.489362 (-5385 5610);
PAINT MONO (-5385 5610);
FORCEPROP 0 LASTPIN (-5375 5500) $PN CP36
J 2
(-5385 5510);
DISPLAY 0.489362 (-5385 5510);
PAINT MONO (-5385 5510);
FORCEPROP 0 LASTPIN (-5375 5400) $PN CT36
J 2
(-5385 5410);
DISPLAY 0.489362 (-5385 5410);
PAINT MONO (-5385 5410);
FORCEPROP 0 LASTPIN (-5375 5300) $PN CN33
J 2
(-5385 5310);
DISPLAY 0.489362 (-5385 5310);
PAINT MONO (-5385 5310);
FORCEPROP 0 LASTPIN (-5375 5200) $PN CU33
J 2
(-5385 5210);
DISPLAY 0.489362 (-5385 5210);
PAINT MONO (-5385 5210);
FORCEPROP 0 LASTPIN (-5375 5100) $PN CR33
J 2
(-5385 5110);
DISPLAY 0.489362 (-5385 5110);
PAINT MONO (-5385 5110);
FORCEPROP 0 LASTPIN (-5375 5000) $PN CN30
J 2
(-5385 5010);
DISPLAY 0.489362 (-5385 5010);
PAINT MONO (-5385 5010);
FORCEPROP 0 LASTPIN (-5375 4900) $PN CU30
J 2
(-5385 4910);
DISPLAY 0.489362 (-5385 4910);
PAINT MONO (-5385 4910);
FORCEPROP 0 LASTPIN (-5375 4800) $PN CR30
J 2
(-5385 4810);
DISPLAY 0.489362 (-5385 4810);
PAINT MONO (-5385 4810);
FORCEPROP 0 LASTPIN (-5375 4700) $PN CL27
J 2
(-5385 4710);
DISPLAY 0.489362 (-5385 4710);
PAINT MONO (-5385 4710);
FORCEPROP 0 LASTPIN (-5375 4600) $PN CU27
J 2
(-5385 4610);
DISPLAY 0.489362 (-5385 4610);
PAINT MONO (-5385 4610);
FORCEPROP 0 LASTPIN (-5375 4500) $PN CR27
J 2
(-5385 4510);
DISPLAY 0.489362 (-5385 4510);
PAINT MONO (-5385 4510);
FORCEPROP 0 LASTPIN (-5375 4400) $PN CN27
J 2
(-5385 4410);
DISPLAY 0.489362 (-5385 4410);
PAINT MONO (-5385 4410);
FORCEPROP 0 LASTPIN (-5375 4300) $PN CL24
J 2
(-5385 4310);
DISPLAY 0.489362 (-5385 4310);
PAINT MONO (-5385 4310);
FORCEPROP 0 LASTPIN (-5375 4200) $PN CR24
J 2
(-5385 4210);
DISPLAY 0.489362 (-5385 4210);
PAINT MONO (-5385 4210);
FORCEPROP 0 LASTPIN (-5375 4100) $PN CN24
J 2
(-5385 4110);
DISPLAY 0.489362 (-5385 4110);
PAINT MONO (-5385 4110);
FORCEPROP 0 LASTPIN (-5375 5650) $PN CM35
J 2
(-5385 5660);
DISPLAY 0.489362 (-5385 5660);
PAINT MONO (-5385 5660);
FORCEPROP 0 LASTPIN (-5375 5550) $PN CP35
J 2
(-5385 5560);
DISPLAY 0.489362 (-5385 5560);
PAINT MONO (-5385 5560);
FORCEPROP 0 LASTPIN (-5375 5450) $PN CT35
J 2
(-5385 5460);
DISPLAY 0.489362 (-5385 5460);
PAINT MONO (-5385 5460);
FORCEPROP 0 LASTPIN (-5375 5350) $PN CN32
J 2
(-5385 5360);
DISPLAY 0.489362 (-5385 5360);
PAINT MONO (-5385 5360);
FORCEPROP 0 LASTPIN (-5375 5250) $PN CU32
J 2
(-5385 5260);
DISPLAY 0.489362 (-5385 5260);
PAINT MONO (-5385 5260);
FORCEPROP 0 LASTPIN (-5375 5150) $PN CR32
J 2
(-5385 5160);
DISPLAY 0.489362 (-5385 5160);
PAINT MONO (-5385 5160);
FORCEPROP 0 LASTPIN (-5375 5050) $PN CN29
J 2
(-5385 5060);
DISPLAY 0.489362 (-5385 5060);
PAINT MONO (-5385 5060);
FORCEPROP 0 LASTPIN (-5375 4950) $PN CU29
J 2
(-5385 4960);
DISPLAY 0.489362 (-5385 4960);
PAINT MONO (-5385 4960);
FORCEPROP 0 LASTPIN (-5375 4850) $PN CR29
J 2
(-5385 4860);
DISPLAY 0.489362 (-5385 4860);
PAINT MONO (-5385 4860);
FORCEPROP 0 LASTPIN (-5375 4750) $PN CL26
J 2
(-5385 4760);
DISPLAY 0.489362 (-5385 4760);
PAINT MONO (-5385 4760);
FORCEPROP 0 LASTPIN (-5375 4650) $PN CU26
J 2
(-5385 4660);
DISPLAY 0.489362 (-5385 4660);
PAINT MONO (-5385 4660);
FORCEPROP 0 LASTPIN (-5375 4550) $PN CR26
J 2
(-5385 4560);
DISPLAY 0.489362 (-5385 4560);
PAINT MONO (-5385 4560);
FORCEPROP 0 LASTPIN (-5375 4450) $PN CN26
J 2
(-5385 4460);
DISPLAY 0.489362 (-5385 4460);
PAINT MONO (-5385 4460);
FORCEPROP 0 LASTPIN (-5375 4350) $PN CL23
J 2
(-5385 4360);
DISPLAY 0.489362 (-5385 4360);
PAINT MONO (-5385 4360);
FORCEPROP 0 LASTPIN (-5375 4250) $PN CR23
J 2
(-5385 4260);
DISPLAY 0.489362 (-5385 4260);
PAINT MONO (-5385 4260);
FORCEPROP 0 LASTPIN (-5375 4150) $PN CN23
J 2
(-5385 4160);
DISPLAY 0.489362 (-5385 4160);
PAINT MONO (-5385 4160);
FORCEPROP 0 LASTPIN (-3875 5600) $PN BT35
J 0
(-3865 5610);
DISPLAY 0.489362 (-3865 5610);
PAINT MONO (-3865 5610);
FORCEPROP 0 LASTPIN (-3875 5500) $PN BV35
J 0
(-3865 5510);
DISPLAY 0.489362 (-3865 5510);
PAINT MONO (-3865 5510);
FORCEPROP 0 LASTPIN (-3875 5400) $PN CB35
J 0
(-3865 5410);
DISPLAY 0.489362 (-3865 5410);
PAINT MONO (-3865 5410);
FORCEPROP 0 LASTPIN (-3875 5300) $PN BY35
J 0
(-3865 5310);
DISPLAY 0.489362 (-3865 5310);
PAINT MONO (-3865 5310);
FORCEPROP 0 LASTPIN (-3875 5200) $PN BU32
J 0
(-3865 5210);
DISPLAY 0.489362 (-3865 5210);
PAINT MONO (-3865 5210);
FORCEPROP 0 LASTPIN (-3875 5100) $PN CA32
J 0
(-3865 5110);
DISPLAY 0.489362 (-3865 5110);
PAINT MONO (-3865 5110);
FORCEPROP 0 LASTPIN (-3875 5000) $PN BW32
J 0
(-3865 5010);
DISPLAY 0.489362 (-3865 5010);
PAINT MONO (-3865 5010);
FORCEPROP 0 LASTPIN (-3875 4900) $PN BU29
J 0
(-3865 4910);
DISPLAY 0.489362 (-3865 4910);
PAINT MONO (-3865 4910);
FORCEPROP 0 LASTPIN (-3875 4800) $PN CA29
J 0
(-3865 4810);
DISPLAY 0.489362 (-3865 4810);
PAINT MONO (-3865 4810);
FORCEPROP 0 LASTPIN (-3875 4700) $PN BW29
J 0
(-3865 4710);
DISPLAY 0.489362 (-3865 4710);
PAINT MONO (-3865 4710);
FORCEPROP 0 LASTPIN (-3875 4600) $PN BU26
J 0
(-3865 4610);
DISPLAY 0.489362 (-3865 4610);
PAINT MONO (-3865 4610);
FORCEPROP 0 LASTPIN (-3875 4500) $PN CA26
J 0
(-3865 4510);
DISPLAY 0.489362 (-3865 4510);
PAINT MONO (-3865 4510);
FORCEPROP 0 LASTPIN (-3875 4400) $PN BW26
J 0
(-3865 4410);
DISPLAY 0.489362 (-3865 4410);
PAINT MONO (-3865 4410);
FORCEPROP 0 LASTPIN (-3875 4300) $PN BU23
J 0
(-3865 4310);
DISPLAY 0.489362 (-3865 4310);
PAINT MONO (-3865 4310);
FORCEPROP 0 LASTPIN (-3875 4200) $PN CA23
J 0
(-3865 4210);
DISPLAY 0.489362 (-3865 4210);
PAINT MONO (-3865 4210);
FORCEPROP 0 LASTPIN (-3875 4100) $PN BW23
J 0
(-3865 4110);
DISPLAY 0.489362 (-3865 4110);
PAINT MONO (-3865 4110);
FORCEPROP 0 LASTPIN (-3875 5650) $PN BT36
J 0
(-3865 5660);
DISPLAY 0.489362 (-3865 5660);
PAINT MONO (-3865 5660);
FORCEPROP 0 LASTPIN (-3875 5550) $PN BV36
J 0
(-3865 5560);
DISPLAY 0.489362 (-3865 5560);
PAINT MONO (-3865 5560);
FORCEPROP 0 LASTPIN (-3875 5450) $PN CB36
J 0
(-3865 5460);
DISPLAY 0.489362 (-3865 5460);
PAINT MONO (-3865 5460);
FORCEPROP 0 LASTPIN (-3875 5350) $PN BY36
J 0
(-3865 5360);
DISPLAY 0.489362 (-3865 5360);
PAINT MONO (-3865 5360);
FORCEPROP 0 LASTPIN (-3875 5250) $PN BU33
J 0
(-3865 5260);
DISPLAY 0.489362 (-3865 5260);
PAINT MONO (-3865 5260);
FORCEPROP 0 LASTPIN (-3875 5150) $PN CA33
J 0
(-3865 5160);
DISPLAY 0.489362 (-3865 5160);
PAINT MONO (-3865 5160);
FORCEPROP 0 LASTPIN (-3875 5050) $PN BW33
J 0
(-3865 5060);
DISPLAY 0.489362 (-3865 5060);
PAINT MONO (-3865 5060);
FORCEPROP 0 LASTPIN (-3875 4950) $PN BU30
J 0
(-3865 4960);
DISPLAY 0.489362 (-3865 4960);
PAINT MONO (-3865 4960);
FORCEPROP 0 LASTPIN (-3875 4850) $PN CA30
J 0
(-3865 4860);
DISPLAY 0.489362 (-3865 4860);
PAINT MONO (-3865 4860);
FORCEPROP 0 LASTPIN (-3875 4750) $PN BW30
J 0
(-3865 4760);
DISPLAY 0.489362 (-3865 4760);
PAINT MONO (-3865 4760);
FORCEPROP 0 LASTPIN (-3875 4650) $PN BU27
J 0
(-3865 4660);
DISPLAY 0.489362 (-3865 4660);
PAINT MONO (-3865 4660);
FORCEPROP 0 LASTPIN (-3875 4550) $PN CA27
J 0
(-3865 4560);
DISPLAY 0.489362 (-3865 4560);
PAINT MONO (-3865 4560);
FORCEPROP 0 LASTPIN (-3875 4450) $PN BW27
J 0
(-3865 4460);
DISPLAY 0.489362 (-3865 4460);
PAINT MONO (-3865 4460);
FORCEPROP 0 LASTPIN (-3875 4350) $PN BU24
J 0
(-3865 4360);
DISPLAY 0.489362 (-3865 4360);
PAINT MONO (-3865 4360);
FORCEPROP 0 LASTPIN (-3875 4250) $PN CA24
J 0
(-3865 4260);
DISPLAY 0.489362 (-3865 4260);
PAINT MONO (-3865 4260);
FORCEPROP 0 LASTPIN (-3875 4150) $PN BW24
J 0
(-3865 4160);
DISPLAY 0.489362 (-3865 4160);
PAINT MONO (-3865 4160);
FORCEPROP 1 LAST MATERIAL IO
J 0
(-5220 5832);
DISPLAY 0.489362 (-5220 5832);
PAINT SKYBLUE (-5220 5832);
FORCEPROP 2 LAST VALUE SOCKET6096_13568-001
J 0
(-5225 5855);
DISPLAY 0.489362 (-5225 5855);
PAINT SKYBLUE (-5225 5855);
FORCEPROP 2 LAST PART_TYPE SMLF
J 0
(-5225 5950);
DISPLAY 1.021277 (-5225 5950);
FORCEPROP 2 LAST CDS_LIB pure_quanta
J 0
(-4625 4850);
DISPLAY INVISIBLE (-4625 4850);
FORCEPROP 1 LAST CDS_LMAN_SYM_OUTLINE -600,950,600,-950
J 0
(-4625 4850);
DISPLAY 0.468085 (-4625 4850);
PAINT GREEN (-4625 4850);
DISPLAY INVISIBLE (-4625 4850);
FORCEPROP 1 LAST NEEDS_NO_SIZE TRUE
J 0
(-4625 4850);
DISPLAY 0.723404 (-4625 4850);
PAINT GREEN (-4625 4850);
DISPLAY INVISIBLE (-4625 4850);
FORCEPROP 1 LAST PATH I148
J 0
(-4625 4850);
DISPLAY 0.723404 (-4625 4850);
PAINT GREEN (-4625 4850);
DISPLAY INVISIBLE (-4625 4850);
FORCEPROP 1 LAST PART_NUMBER DGA^6000030
J 0
(-5225 5900);
DISPLAY 0.489362 (-5225 5900);
PAINT SKYBLUE (-5225 5900);
DISPLAY INVISIBLE (-5225 5900);
FORCEADD OFFPAGE..2
(-2325 5825);
FORCEPROP 2 LAST $XR0 66 
J 0
(-2136 5825);
DISPLAY 0.638298 (-2136 5825);
PAINT MONO (-2136 5825);
FORCEPROP 2 LAST CDS_LIB standard
J 0
(-2325 5825);
DISPLAY INVISIBLE (-2325 5825);
FORCEPROP 1 LAST OFFPAGE TRUE
J 0
(-2000 5700);
DISPLAY 0.872340 (-2000 5700);
PAINT GREEN (-2000 5700);
DISPLAY INVISIBLE (-2000 5700);
FORCEPROP 1 LAST COMMENT_BODY TRUE
J 0
(-2370 5730);
DISPLAY 0.872340 (-2370 5730);
PAINT GREEN (-2370 5730);
DISPLAY INVISIBLE (-2370 5730);
FORCEPROP 2 LAST PATH I149
J 0
(-2150 5900);
DISPLAY 1.021277 (-2150 5900);
DISPLAY INVISIBLE (-2150 5900);
FORCEADD OFFPAGE..2
(-2325 5875);
FORCEPROP 2 LAST $XR0 66 
J 0
(-2136 5875);
DISPLAY 0.638298 (-2136 5875);
PAINT MONO (-2136 5875);
FORCEPROP 2 LAST CDS_LIB standard
J 0
(-2325 5875);
DISPLAY INVISIBLE (-2325 5875);
FORCEPROP 1 LAST OFFPAGE TRUE
J 0
(-2000 5750);
DISPLAY 0.872340 (-2000 5750);
PAINT GREEN (-2000 5750);
DISPLAY INVISIBLE (-2000 5750);
FORCEPROP 1 LAST COMMENT_BODY TRUE
J 0
(-2370 5780);
DISPLAY 0.872340 (-2370 5780);
PAINT GREEN (-2370 5780);
DISPLAY INVISIBLE (-2370 5780);
FORCEPROP 2 LAST PATH I150
J 0
(-2150 5950);
DISPLAY 1.021277 (-2150 5950);
DISPLAY INVISIBLE (-2150 5950);
FORCEADD TAP..6
R 2
(-3450 5650);
FORCEPROP 3 LASTPIN (-3500 5650) SIG_NAME P5E_CPU1_P2_TX_DP<0>
J 0
(-3490 5660);
DISPLAY 0.659574 (-3490 5660);
PAINT MONO (-3490 5660);
DISPLAY INVISIBLE (-3490 5660);
FORCEPROP 1 LASTPIN (-3500 5650) BN 0
J 2
(-3448 5658);
DISPLAY 0.489362 (-3448 5658);
PAINT MONO (-3448 5658);
FORCEPROP 2 LAST CDS_LIB mstr_standard
J 0
(-3450 5650);
DISPLAY INVISIBLE (-3450 5650);
FORCEPROP 2 LAST BOM_COST IO_SLOT
J 0
(-3950 5750);
DISPLAY 0.829787 (-3950 5750);
DISPLAY INVISIBLE (-3950 5750);
FORCEPROP 2 LAST ROOM RISER1
J 0
(-3950 5700);
DISPLAY 0.829787 (-3950 5700);
PAINT RED (-3950 5700);
DISPLAY INVISIBLE (-3950 5700);
FORCEPROP 1 LAST BODY_TYPE PLUMBING
J 2
(-3450 5600);
DISPLAY 0.702128 (-3450 5600);
PAINT GREEN (-3450 5600);
DISPLAY INVISIBLE (-3450 5600);
FORCEPROP 1 LAST HDL_TAP TRUE
J 2
(-3775 5525);
DISPLAY 0.702128 (-3775 5525);
PAINT GREEN (-3775 5525);
DISPLAY INVISIBLE (-3775 5525);
FORCEPROP 1 LAST PATH I151
J 2
(-3448 5650);
DISPLAY 0.872340 (-3448 5650);
PAINT GREEN (-3448 5650);
DISPLAY INVISIBLE (-3448 5650);
FORCEADD TAP..6
R 2
(-3300 5500);
FORCEPROP 3 LASTPIN (-3350 5500) SIG_NAME P5E_CPU1_P2_TX_DN<1>
J 0
(-3340 5510);
DISPLAY 0.659574 (-3340 5510);
PAINT MONO (-3340 5510);
DISPLAY INVISIBLE (-3340 5510);
FORCEPROP 1 LASTPIN (-3350 5500) BN 1
J 2
(-3298 5508);
DISPLAY 0.489362 (-3298 5508);
PAINT MONO (-3298 5508);
FORCEPROP 2 LAST CDS_LIB mstr_standard
J 0
(-3300 5500);
DISPLAY INVISIBLE (-3300 5500);
FORCEPROP 2 LAST BOM_COST IO_SLOT
J 0
(-3800 5600);
DISPLAY 0.829787 (-3800 5600);
DISPLAY INVISIBLE (-3800 5600);
FORCEPROP 2 LAST ROOM RISER1
J 0
(-3800 5550);
DISPLAY 0.829787 (-3800 5550);
PAINT RED (-3800 5550);
DISPLAY INVISIBLE (-3800 5550);
FORCEPROP 1 LAST BODY_TYPE PLUMBING
J 2
(-3300 5450);
DISPLAY 0.702128 (-3300 5450);
PAINT GREEN (-3300 5450);
DISPLAY INVISIBLE (-3300 5450);
FORCEPROP 1 LAST HDL_TAP TRUE
J 2
(-3625 5375);
DISPLAY 0.702128 (-3625 5375);
PAINT GREEN (-3625 5375);
DISPLAY INVISIBLE (-3625 5375);
FORCEPROP 1 LAST PATH I152
J 2
(-3298 5500);
DISPLAY 0.872340 (-3298 5500);
PAINT GREEN (-3298 5500);
DISPLAY INVISIBLE (-3298 5500);
FORCEADD TAP..6
R 2
(-3300 5400);
FORCEPROP 3 LASTPIN (-3350 5400) SIG_NAME P5E_CPU1_P2_TX_DN<2>
J 0
(-3340 5410);
DISPLAY 0.659574 (-3340 5410);
PAINT MONO (-3340 5410);
DISPLAY INVISIBLE (-3340 5410);
FORCEPROP 1 LASTPIN (-3350 5400) BN 2
J 2
(-3298 5408);
DISPLAY 0.489362 (-3298 5408);
PAINT MONO (-3298 5408);
FORCEPROP 2 LAST CDS_LIB standard
J 0
(-3300 5400);
DISPLAY INVISIBLE (-3300 5400);
FORCEPROP 2 LAST BOM_COST IO_SLOT
J 0
(-3800 5500);
DISPLAY 0.829787 (-3800 5500);
DISPLAY INVISIBLE (-3800 5500);
FORCEPROP 2 LAST ROOM RISER1
J 0
(-3800 5450);
DISPLAY 0.829787 (-3800 5450);
PAINT RED (-3800 5450);
DISPLAY INVISIBLE (-3800 5450);
FORCEPROP 1 LAST BODY_TYPE PLUMBING
J 2
(-3300 5350);
DISPLAY 0.702128 (-3300 5350);
PAINT GREEN (-3300 5350);
DISPLAY INVISIBLE (-3300 5350);
FORCEPROP 1 LAST HDL_TAP TRUE
J 2
(-3625 5275);
DISPLAY 0.702128 (-3625 5275);
PAINT GREEN (-3625 5275);
DISPLAY INVISIBLE (-3625 5275);
FORCEPROP 1 LAST PATH I153
J 2
(-3298 5400);
DISPLAY 0.872340 (-3298 5400);
PAINT GREEN (-3298 5400);
DISPLAY INVISIBLE (-3298 5400);
FORCEADD TAP..6
R 2
(-3300 5600);
FORCEPROP 3 LASTPIN (-3350 5600) SIG_NAME P5E_CPU1_P2_TX_DN<0>
J 0
(-3340 5610);
DISPLAY 0.659574 (-3340 5610);
PAINT MONO (-3340 5610);
DISPLAY INVISIBLE (-3340 5610);
FORCEPROP 1 LASTPIN (-3350 5600) BN 0
J 2
(-3298 5608);
DISPLAY 0.489362 (-3298 5608);
PAINT MONO (-3298 5608);
FORCEPROP 2 LAST BOM_COST IO_SLOT
J 0
(-3800 5700);
DISPLAY 0.829787 (-3800 5700);
DISPLAY INVISIBLE (-3800 5700);
FORCEPROP 2 LAST CDS_LIB mstr_standard
J 0
(-3300 5600);
DISPLAY INVISIBLE (-3300 5600);
FORCEPROP 2 LAST ROOM RISER1
J 0
(-3800 5650);
DISPLAY 0.829787 (-3800 5650);
PAINT RED (-3800 5650);
DISPLAY INVISIBLE (-3800 5650);
FORCEPROP 1 LAST BODY_TYPE PLUMBING
J 2
(-3300 5550);
DISPLAY 0.702128 (-3300 5550);
PAINT GREEN (-3300 5550);
DISPLAY INVISIBLE (-3300 5550);
FORCEPROP 1 LAST HDL_TAP TRUE
J 2
(-3625 5475);
DISPLAY 0.702128 (-3625 5475);
PAINT GREEN (-3625 5475);
DISPLAY INVISIBLE (-3625 5475);
FORCEPROP 1 LAST PATH I154
J 2
(-3298 5600);
DISPLAY 0.872340 (-3298 5600);
PAINT GREEN (-3298 5600);
DISPLAY INVISIBLE (-3298 5600);
FORCEADD TAP..6
R 2
(-3450 5550);
FORCEPROP 3 LASTPIN (-3500 5550) SIG_NAME P5E_CPU1_P2_TX_DP<1>
J 0
(-3490 5560);
DISPLAY 0.659574 (-3490 5560);
PAINT MONO (-3490 5560);
DISPLAY INVISIBLE (-3490 5560);
FORCEPROP 1 LASTPIN (-3500 5550) BN 1
J 2
(-3448 5558);
DISPLAY 0.489362 (-3448 5558);
PAINT MONO (-3448 5558);
FORCEPROP 2 LAST CDS_LIB mstr_standard
J 0
(-3450 5550);
DISPLAY INVISIBLE (-3450 5550);
FORCEPROP 2 LAST BOM_COST IO_SLOT
J 0
(-3950 5650);
DISPLAY 0.829787 (-3950 5650);
DISPLAY INVISIBLE (-3950 5650);
FORCEPROP 2 LAST ROOM RISER1
J 0
(-3950 5600);
DISPLAY 0.829787 (-3950 5600);
PAINT RED (-3950 5600);
DISPLAY INVISIBLE (-3950 5600);
FORCEPROP 1 LAST BODY_TYPE PLUMBING
J 2
(-3450 5500);
DISPLAY 0.702128 (-3450 5500);
PAINT GREEN (-3450 5500);
DISPLAY INVISIBLE (-3450 5500);
FORCEPROP 1 LAST HDL_TAP TRUE
J 2
(-3775 5425);
DISPLAY 0.702128 (-3775 5425);
PAINT GREEN (-3775 5425);
DISPLAY INVISIBLE (-3775 5425);
FORCEPROP 1 LAST PATH I155
J 2
(-3448 5550);
DISPLAY 0.872340 (-3448 5550);
PAINT GREEN (-3448 5550);
DISPLAY INVISIBLE (-3448 5550);
FORCEADD TAP..6
R 2
(-3450 5450);
FORCEPROP 3 LASTPIN (-3500 5450) SIG_NAME P5E_CPU1_P2_TX_DP<2>
J 0
(-3490 5460);
DISPLAY 0.659574 (-3490 5460);
PAINT MONO (-3490 5460);
DISPLAY INVISIBLE (-3490 5460);
FORCEPROP 1 LASTPIN (-3500 5450) BN 2
J 2
(-3448 5458);
DISPLAY 0.489362 (-3448 5458);
PAINT MONO (-3448 5458);
FORCEPROP 2 LAST CDS_LIB standard
J 0
(-3450 5450);
DISPLAY INVISIBLE (-3450 5450);
FORCEPROP 2 LAST BOM_COST IO_SLOT
J 0
(-3950 5550);
DISPLAY 0.829787 (-3950 5550);
DISPLAY INVISIBLE (-3950 5550);
FORCEPROP 2 LAST ROOM RISER1
J 0
(-3950 5500);
DISPLAY 0.829787 (-3950 5500);
PAINT RED (-3950 5500);
DISPLAY INVISIBLE (-3950 5500);
FORCEPROP 1 LAST BODY_TYPE PLUMBING
J 2
(-3450 5400);
DISPLAY 0.702128 (-3450 5400);
PAINT GREEN (-3450 5400);
DISPLAY INVISIBLE (-3450 5400);
FORCEPROP 1 LAST HDL_TAP TRUE
J 2
(-3775 5325);
DISPLAY 0.702128 (-3775 5325);
PAINT GREEN (-3775 5325);
DISPLAY INVISIBLE (-3775 5325);
FORCEPROP 1 LAST PATH I156
J 2
(-3448 5450);
DISPLAY 0.872340 (-3448 5450);
PAINT GREEN (-3448 5450);
DISPLAY INVISIBLE (-3448 5450);
FORCEADD TAP..6
R 2
(-3300 5300);
FORCEPROP 3 LASTPIN (-3350 5300) SIG_NAME P5E_CPU1_P2_TX_DN<3>
J 0
(-3340 5310);
DISPLAY 0.659574 (-3340 5310);
PAINT MONO (-3340 5310);
DISPLAY INVISIBLE (-3340 5310);
FORCEPROP 1 LASTPIN (-3350 5300) BN 3
J 2
(-3298 5308);
DISPLAY 0.489362 (-3298 5308);
PAINT MONO (-3298 5308);
FORCEPROP 2 LAST CDS_LIB standard
J 0
(-3300 5300);
DISPLAY INVISIBLE (-3300 5300);
FORCEPROP 2 LAST BOM_COST IO_SLOT
J 0
(-3800 5400);
DISPLAY 0.829787 (-3800 5400);
DISPLAY INVISIBLE (-3800 5400);
FORCEPROP 2 LAST ROOM RISER1
J 0
(-3800 5350);
DISPLAY 0.829787 (-3800 5350);
PAINT RED (-3800 5350);
DISPLAY INVISIBLE (-3800 5350);
FORCEPROP 1 LAST BODY_TYPE PLUMBING
J 2
(-3300 5250);
DISPLAY 0.702128 (-3300 5250);
PAINT GREEN (-3300 5250);
DISPLAY INVISIBLE (-3300 5250);
FORCEPROP 1 LAST HDL_TAP TRUE
J 2
(-3625 5175);
DISPLAY 0.702128 (-3625 5175);
PAINT GREEN (-3625 5175);
DISPLAY INVISIBLE (-3625 5175);
FORCEPROP 1 LAST PATH I157
J 2
(-3298 5300);
DISPLAY 0.872340 (-3298 5300);
PAINT GREEN (-3298 5300);
DISPLAY INVISIBLE (-3298 5300);
FORCEADD TAP..6
R 2
(-3300 5200);
FORCEPROP 3 LASTPIN (-3350 5200) SIG_NAME P5E_CPU1_P2_TX_DN<4>
J 0
(-3340 5210);
DISPLAY 0.659574 (-3340 5210);
PAINT MONO (-3340 5210);
DISPLAY INVISIBLE (-3340 5210);
FORCEPROP 1 LASTPIN (-3350 5200) BN 4
J 2
(-3298 5208);
DISPLAY 0.489362 (-3298 5208);
PAINT MONO (-3298 5208);
FORCEPROP 2 LAST CDS_LIB standard
J 0
(-3300 5200);
DISPLAY INVISIBLE (-3300 5200);
FORCEPROP 2 LAST BOM_COST IO_SLOT
J 0
(-3800 5300);
DISPLAY 0.829787 (-3800 5300);
DISPLAY INVISIBLE (-3800 5300);
FORCEPROP 2 LAST ROOM RISER1
J 0
(-3800 5250);
DISPLAY 0.829787 (-3800 5250);
PAINT RED (-3800 5250);
DISPLAY INVISIBLE (-3800 5250);
FORCEPROP 1 LAST BODY_TYPE PLUMBING
J 2
(-3300 5150);
DISPLAY 0.702128 (-3300 5150);
PAINT GREEN (-3300 5150);
DISPLAY INVISIBLE (-3300 5150);
FORCEPROP 1 LAST HDL_TAP TRUE
J 2
(-3625 5075);
DISPLAY 0.702128 (-3625 5075);
PAINT GREEN (-3625 5075);
DISPLAY INVISIBLE (-3625 5075);
FORCEPROP 1 LAST PATH I158
J 2
(-3298 5200);
DISPLAY 0.872340 (-3298 5200);
PAINT GREEN (-3298 5200);
DISPLAY INVISIBLE (-3298 5200);
FORCEADD TAP..6
R 2
(-3450 5250);
FORCEPROP 3 LASTPIN (-3500 5250) SIG_NAME P5E_CPU1_P2_TX_DP<4>
J 0
(-3490 5260);
DISPLAY 0.659574 (-3490 5260);
PAINT MONO (-3490 5260);
DISPLAY INVISIBLE (-3490 5260);
FORCEPROP 1 LASTPIN (-3500 5250) BN 4
J 2
(-3448 5258);
DISPLAY 0.489362 (-3448 5258);
PAINT MONO (-3448 5258);
FORCEPROP 2 LAST CDS_LIB standard
J 0
(-3450 5250);
DISPLAY INVISIBLE (-3450 5250);
FORCEPROP 2 LAST BOM_COST IO_SLOT
J 0
(-3950 5350);
DISPLAY 0.829787 (-3950 5350);
DISPLAY INVISIBLE (-3950 5350);
FORCEPROP 2 LAST ROOM RISER1
J 0
(-3950 5300);
DISPLAY 0.829787 (-3950 5300);
PAINT RED (-3950 5300);
DISPLAY INVISIBLE (-3950 5300);
FORCEPROP 1 LAST BODY_TYPE PLUMBING
J 2
(-3450 5200);
DISPLAY 0.702128 (-3450 5200);
PAINT GREEN (-3450 5200);
DISPLAY INVISIBLE (-3450 5200);
FORCEPROP 1 LAST HDL_TAP TRUE
J 2
(-3775 5125);
DISPLAY 0.702128 (-3775 5125);
PAINT GREEN (-3775 5125);
DISPLAY INVISIBLE (-3775 5125);
FORCEPROP 1 LAST PATH I159
J 2
(-3448 5250);
DISPLAY 0.872340 (-3448 5250);
PAINT GREEN (-3448 5250);
DISPLAY INVISIBLE (-3448 5250);
FORCEADD TAP..6
R 2
(-3450 5350);
FORCEPROP 3 LASTPIN (-3500 5350) SIG_NAME P5E_CPU1_P2_TX_DP<3>
J 0
(-3490 5360);
DISPLAY 0.659574 (-3490 5360);
PAINT MONO (-3490 5360);
DISPLAY INVISIBLE (-3490 5360);
FORCEPROP 1 LASTPIN (-3500 5350) BN 3
J 2
(-3448 5358);
DISPLAY 0.489362 (-3448 5358);
PAINT MONO (-3448 5358);
FORCEPROP 2 LAST CDS_LIB standard
J 0
(-3450 5350);
DISPLAY INVISIBLE (-3450 5350);
FORCEPROP 2 LAST BOM_COST IO_SLOT
J 0
(-3950 5450);
DISPLAY 0.829787 (-3950 5450);
DISPLAY INVISIBLE (-3950 5450);
FORCEPROP 2 LAST ROOM RISER1
J 0
(-3950 5400);
DISPLAY 0.829787 (-3950 5400);
PAINT RED (-3950 5400);
DISPLAY INVISIBLE (-3950 5400);
FORCEPROP 1 LAST BODY_TYPE PLUMBING
J 2
(-3450 5300);
DISPLAY 0.702128 (-3450 5300);
PAINT GREEN (-3450 5300);
DISPLAY INVISIBLE (-3450 5300);
FORCEPROP 1 LAST HDL_TAP TRUE
J 2
(-3775 5225);
DISPLAY 0.702128 (-3775 5225);
PAINT GREEN (-3775 5225);
DISPLAY INVISIBLE (-3775 5225);
FORCEPROP 1 LAST PATH I160
J 2
(-3448 5350);
DISPLAY 0.872340 (-3448 5350);
PAINT GREEN (-3448 5350);
DISPLAY INVISIBLE (-3448 5350);
FORCEADD TAP..6
R 2
(-3450 5150);
FORCEPROP 3 LASTPIN (-3500 5150) SIG_NAME P5E_CPU1_P2_TX_DP<5>
J 0
(-3490 5160);
DISPLAY 0.659574 (-3490 5160);
PAINT MONO (-3490 5160);
DISPLAY INVISIBLE (-3490 5160);
FORCEPROP 1 LASTPIN (-3500 5150) BN 5
J 2
(-3448 5158);
DISPLAY 0.489362 (-3448 5158);
PAINT MONO (-3448 5158);
FORCEPROP 2 LAST CDS_LIB standard
J 0
(-3450 5150);
DISPLAY INVISIBLE (-3450 5150);
FORCEPROP 2 LAST BOM_COST IO_SLOT
J 0
(-3950 5250);
DISPLAY 0.829787 (-3950 5250);
DISPLAY INVISIBLE (-3950 5250);
FORCEPROP 2 LAST ROOM RISER1
J 0
(-3950 5200);
DISPLAY 0.829787 (-3950 5200);
PAINT RED (-3950 5200);
DISPLAY INVISIBLE (-3950 5200);
FORCEPROP 1 LAST BODY_TYPE PLUMBING
J 2
(-3450 5100);
DISPLAY 0.702128 (-3450 5100);
PAINT GREEN (-3450 5100);
DISPLAY INVISIBLE (-3450 5100);
FORCEPROP 1 LAST HDL_TAP TRUE
J 2
(-3775 5025);
DISPLAY 0.702128 (-3775 5025);
PAINT GREEN (-3775 5025);
DISPLAY INVISIBLE (-3775 5025);
FORCEPROP 1 LAST PATH I161
J 2
(-3448 5150);
DISPLAY 0.872340 (-3448 5150);
PAINT GREEN (-3448 5150);
DISPLAY INVISIBLE (-3448 5150);
FORCEADD TAP..6
R 2
(-3300 5000);
FORCEPROP 3 LASTPIN (-3350 5000) SIG_NAME P5E_CPU1_P2_TX_DN<6>
J 0
(-3340 5010);
DISPLAY 0.659574 (-3340 5010);
PAINT MONO (-3340 5010);
DISPLAY INVISIBLE (-3340 5010);
FORCEPROP 1 LASTPIN (-3350 5000) BN 6
J 2
(-3298 5008);
DISPLAY 0.489362 (-3298 5008);
PAINT MONO (-3298 5008);
FORCEPROP 2 LAST CDS_LIB standard
J 0
(-3300 5000);
DISPLAY INVISIBLE (-3300 5000);
FORCEPROP 2 LAST BOM_COST IO_SLOT
J 0
(-3800 5100);
DISPLAY 0.829787 (-3800 5100);
DISPLAY INVISIBLE (-3800 5100);
FORCEPROP 2 LAST ROOM RISER1
J 0
(-3800 5050);
DISPLAY 0.829787 (-3800 5050);
PAINT RED (-3800 5050);
DISPLAY INVISIBLE (-3800 5050);
FORCEPROP 1 LAST BODY_TYPE PLUMBING
J 2
(-3300 4950);
DISPLAY 0.702128 (-3300 4950);
PAINT GREEN (-3300 4950);
DISPLAY INVISIBLE (-3300 4950);
FORCEPROP 1 LAST HDL_TAP TRUE
J 2
(-3625 4875);
DISPLAY 0.702128 (-3625 4875);
PAINT GREEN (-3625 4875);
DISPLAY INVISIBLE (-3625 4875);
FORCEPROP 1 LAST PATH I162
J 2
(-3298 5000);
DISPLAY 0.872340 (-3298 5000);
PAINT GREEN (-3298 5000);
DISPLAY INVISIBLE (-3298 5000);
FORCEADD TAP..6
R 2
(-3300 5100);
FORCEPROP 3 LASTPIN (-3350 5100) SIG_NAME P5E_CPU1_P2_TX_DN<5>
J 0
(-3340 5110);
DISPLAY 0.659574 (-3340 5110);
PAINT MONO (-3340 5110);
DISPLAY INVISIBLE (-3340 5110);
FORCEPROP 1 LASTPIN (-3350 5100) BN 5
J 2
(-3298 5108);
DISPLAY 0.489362 (-3298 5108);
PAINT MONO (-3298 5108);
FORCEPROP 2 LAST CDS_LIB standard
J 0
(-3300 5100);
DISPLAY INVISIBLE (-3300 5100);
FORCEPROP 2 LAST BOM_COST IO_SLOT
J 0
(-3800 5200);
DISPLAY 0.829787 (-3800 5200);
DISPLAY INVISIBLE (-3800 5200);
FORCEPROP 2 LAST ROOM RISER1
J 0
(-3800 5150);
DISPLAY 0.829787 (-3800 5150);
PAINT RED (-3800 5150);
DISPLAY INVISIBLE (-3800 5150);
FORCEPROP 1 LAST BODY_TYPE PLUMBING
J 2
(-3300 5050);
DISPLAY 0.702128 (-3300 5050);
PAINT GREEN (-3300 5050);
DISPLAY INVISIBLE (-3300 5050);
FORCEPROP 1 LAST HDL_TAP TRUE
J 2
(-3625 4975);
DISPLAY 0.702128 (-3625 4975);
PAINT GREEN (-3625 4975);
DISPLAY INVISIBLE (-3625 4975);
FORCEPROP 1 LAST PATH I163
J 2
(-3298 5100);
DISPLAY 0.872340 (-3298 5100);
PAINT GREEN (-3298 5100);
DISPLAY INVISIBLE (-3298 5100);
FORCEADD TAP..6
R 2
(-3300 4900);
FORCEPROP 3 LASTPIN (-3350 4900) SIG_NAME P5E_CPU1_P2_TX_DN<7>
J 0
(-3340 4910);
DISPLAY 0.659574 (-3340 4910);
PAINT MONO (-3340 4910);
DISPLAY INVISIBLE (-3340 4910);
FORCEPROP 1 LASTPIN (-3350 4900) BN 7
J 2
(-3298 4908);
DISPLAY 0.489362 (-3298 4908);
PAINT MONO (-3298 4908);
FORCEPROP 2 LAST CDS_LIB standard
J 0
(-3300 4900);
DISPLAY INVISIBLE (-3300 4900);
FORCEPROP 2 LAST BOM_COST IO_SLOT
J 0
(-3800 5000);
DISPLAY 0.829787 (-3800 5000);
DISPLAY INVISIBLE (-3800 5000);
FORCEPROP 2 LAST ROOM RISER1
J 0
(-3800 4950);
DISPLAY 0.829787 (-3800 4950);
PAINT RED (-3800 4950);
DISPLAY INVISIBLE (-3800 4950);
FORCEPROP 1 LAST BODY_TYPE PLUMBING
J 2
(-3300 4850);
DISPLAY 0.702128 (-3300 4850);
PAINT GREEN (-3300 4850);
DISPLAY INVISIBLE (-3300 4850);
FORCEPROP 1 LAST HDL_TAP TRUE
J 2
(-3625 4775);
DISPLAY 0.702128 (-3625 4775);
PAINT GREEN (-3625 4775);
DISPLAY INVISIBLE (-3625 4775);
FORCEPROP 1 LAST PATH I164
J 2
(-3298 4900);
DISPLAY 0.872340 (-3298 4900);
PAINT GREEN (-3298 4900);
DISPLAY INVISIBLE (-3298 4900);
FORCEADD TAP..6
R 2
(-3450 4950);
FORCEPROP 3 LASTPIN (-3500 4950) SIG_NAME P5E_CPU1_P2_TX_DP<7>
J 0
(-3490 4960);
DISPLAY 0.659574 (-3490 4960);
PAINT MONO (-3490 4960);
DISPLAY INVISIBLE (-3490 4960);
FORCEPROP 1 LASTPIN (-3500 4950) BN 7
J 2
(-3448 4958);
DISPLAY 0.489362 (-3448 4958);
PAINT MONO (-3448 4958);
FORCEPROP 2 LAST CDS_LIB standard
J 0
(-3450 4950);
DISPLAY INVISIBLE (-3450 4950);
FORCEPROP 2 LAST BOM_COST IO_SLOT
J 0
(-3950 5050);
DISPLAY 0.829787 (-3950 5050);
DISPLAY INVISIBLE (-3950 5050);
FORCEPROP 2 LAST ROOM RISER1
J 0
(-3950 5000);
DISPLAY 0.829787 (-3950 5000);
PAINT RED (-3950 5000);
DISPLAY INVISIBLE (-3950 5000);
FORCEPROP 1 LAST BODY_TYPE PLUMBING
J 2
(-3450 4900);
DISPLAY 0.702128 (-3450 4900);
PAINT GREEN (-3450 4900);
DISPLAY INVISIBLE (-3450 4900);
FORCEPROP 1 LAST HDL_TAP TRUE
J 2
(-3775 4825);
DISPLAY 0.702128 (-3775 4825);
PAINT GREEN (-3775 4825);
DISPLAY INVISIBLE (-3775 4825);
FORCEPROP 1 LAST PATH I165
J 2
(-3448 4950);
DISPLAY 0.872340 (-3448 4950);
PAINT GREEN (-3448 4950);
DISPLAY INVISIBLE (-3448 4950);
FORCEADD TAP..6
R 2
(-3450 5050);
FORCEPROP 3 LASTPIN (-3500 5050) SIG_NAME P5E_CPU1_P2_TX_DP<6>
J 0
(-3490 5060);
DISPLAY 0.659574 (-3490 5060);
PAINT MONO (-3490 5060);
DISPLAY INVISIBLE (-3490 5060);
FORCEPROP 1 LASTPIN (-3500 5050) BN 6
J 2
(-3448 5058);
DISPLAY 0.489362 (-3448 5058);
PAINT MONO (-3448 5058);
FORCEPROP 2 LAST CDS_LIB standard
J 0
(-3450 5050);
DISPLAY INVISIBLE (-3450 5050);
FORCEPROP 2 LAST BOM_COST IO_SLOT
J 0
(-3950 5150);
DISPLAY 0.829787 (-3950 5150);
DISPLAY INVISIBLE (-3950 5150);
FORCEPROP 2 LAST ROOM RISER1
J 0
(-3950 5100);
DISPLAY 0.829787 (-3950 5100);
PAINT RED (-3950 5100);
DISPLAY INVISIBLE (-3950 5100);
FORCEPROP 1 LAST BODY_TYPE PLUMBING
J 2
(-3450 5000);
DISPLAY 0.702128 (-3450 5000);
PAINT GREEN (-3450 5000);
DISPLAY INVISIBLE (-3450 5000);
FORCEPROP 1 LAST HDL_TAP TRUE
J 2
(-3775 4925);
DISPLAY 0.702128 (-3775 4925);
PAINT GREEN (-3775 4925);
DISPLAY INVISIBLE (-3775 4925);
FORCEPROP 1 LAST PATH I166
J 2
(-3448 5050);
DISPLAY 0.872340 (-3448 5050);
PAINT GREEN (-3448 5050);
DISPLAY INVISIBLE (-3448 5050);
FORCEADD TAP..6
R 2
(-3300 4700);
FORCEPROP 3 LASTPIN (-3350 4700) SIG_NAME P5E_CPU1_P2_TX_DN<9>
J 0
(-3340 4710);
DISPLAY 0.659574 (-3340 4710);
PAINT MONO (-3340 4710);
DISPLAY INVISIBLE (-3340 4710);
FORCEPROP 1 LASTPIN (-3350 4700) BN 9
J 2
(-3298 4708);
DISPLAY 0.489362 (-3298 4708);
PAINT MONO (-3298 4708);
FORCEPROP 2 LAST CDS_LIB standard
J 0
(-3300 4700);
DISPLAY INVISIBLE (-3300 4700);
FORCEPROP 2 LAST BOM_COST IO_SLOT
J 0
(-3800 4800);
DISPLAY 0.829787 (-3800 4800);
DISPLAY INVISIBLE (-3800 4800);
FORCEPROP 2 LAST ROOM RISER1
J 0
(-3800 4750);
DISPLAY 0.829787 (-3800 4750);
PAINT RED (-3800 4750);
DISPLAY INVISIBLE (-3800 4750);
FORCEPROP 1 LAST BODY_TYPE PLUMBING
J 2
(-3300 4650);
DISPLAY 0.702128 (-3300 4650);
PAINT GREEN (-3300 4650);
DISPLAY INVISIBLE (-3300 4650);
FORCEPROP 1 LAST HDL_TAP TRUE
J 2
(-3625 4575);
DISPLAY 0.702128 (-3625 4575);
PAINT GREEN (-3625 4575);
DISPLAY INVISIBLE (-3625 4575);
FORCEPROP 1 LAST PATH I167
J 2
(-3298 4700);
DISPLAY 0.872340 (-3298 4700);
PAINT GREEN (-3298 4700);
DISPLAY INVISIBLE (-3298 4700);
FORCEADD TAP..6
R 2
(-3300 4800);
FORCEPROP 3 LASTPIN (-3350 4800) SIG_NAME P5E_CPU1_P2_TX_DN<8>
J 0
(-3340 4810);
DISPLAY 0.659574 (-3340 4810);
PAINT MONO (-3340 4810);
DISPLAY INVISIBLE (-3340 4810);
FORCEPROP 1 LASTPIN (-3350 4800) BN 8
J 2
(-3298 4808);
DISPLAY 0.489362 (-3298 4808);
PAINT MONO (-3298 4808);
FORCEPROP 2 LAST CDS_LIB standard
J 0
(-3300 4800);
DISPLAY INVISIBLE (-3300 4800);
FORCEPROP 2 LAST BOM_COST IO_SLOT
J 0
(-3800 4900);
DISPLAY 0.829787 (-3800 4900);
DISPLAY INVISIBLE (-3800 4900);
FORCEPROP 2 LAST ROOM RISER1
J 0
(-3800 4850);
DISPLAY 0.829787 (-3800 4850);
PAINT RED (-3800 4850);
DISPLAY INVISIBLE (-3800 4850);
FORCEPROP 1 LAST BODY_TYPE PLUMBING
J 2
(-3300 4750);
DISPLAY 0.702128 (-3300 4750);
PAINT GREEN (-3300 4750);
DISPLAY INVISIBLE (-3300 4750);
FORCEPROP 1 LAST HDL_TAP TRUE
J 2
(-3625 4675);
DISPLAY 0.702128 (-3625 4675);
PAINT GREEN (-3625 4675);
DISPLAY INVISIBLE (-3625 4675);
FORCEPROP 1 LAST PATH I168
J 2
(-3298 4800);
DISPLAY 0.872340 (-3298 4800);
PAINT GREEN (-3298 4800);
DISPLAY INVISIBLE (-3298 4800);
FORCEADD TAP..6
R 2
(-3450 4850);
FORCEPROP 3 LASTPIN (-3500 4850) SIG_NAME P5E_CPU1_P2_TX_DP<8>
J 0
(-3490 4860);
DISPLAY 0.659574 (-3490 4860);
PAINT MONO (-3490 4860);
DISPLAY INVISIBLE (-3490 4860);
FORCEPROP 1 LASTPIN (-3500 4850) BN 8
J 2
(-3448 4858);
DISPLAY 0.489362 (-3448 4858);
PAINT MONO (-3448 4858);
FORCEPROP 2 LAST CDS_LIB standard
J 0
(-3450 4850);
DISPLAY INVISIBLE (-3450 4850);
FORCEPROP 2 LAST BOM_COST IO_SLOT
J 0
(-3950 4950);
DISPLAY 0.829787 (-3950 4950);
DISPLAY INVISIBLE (-3950 4950);
FORCEPROP 2 LAST ROOM RISER1
J 0
(-3950 4900);
DISPLAY 0.829787 (-3950 4900);
PAINT RED (-3950 4900);
DISPLAY INVISIBLE (-3950 4900);
FORCEPROP 1 LAST BODY_TYPE PLUMBING
J 2
(-3450 4800);
DISPLAY 0.702128 (-3450 4800);
PAINT GREEN (-3450 4800);
DISPLAY INVISIBLE (-3450 4800);
FORCEPROP 1 LAST HDL_TAP TRUE
J 2
(-3775 4725);
DISPLAY 0.702128 (-3775 4725);
PAINT GREEN (-3775 4725);
DISPLAY INVISIBLE (-3775 4725);
FORCEPROP 1 LAST PATH I169
J 2
(-3448 4850);
DISPLAY 0.872340 (-3448 4850);
PAINT GREEN (-3448 4850);
DISPLAY INVISIBLE (-3448 4850);
FORCEADD TAP..6
R 2
(-3450 4750);
FORCEPROP 3 LASTPIN (-3500 4750) SIG_NAME P5E_CPU1_P2_TX_DP<9>
J 0
(-3490 4760);
DISPLAY 0.659574 (-3490 4760);
PAINT MONO (-3490 4760);
DISPLAY INVISIBLE (-3490 4760);
FORCEPROP 1 LASTPIN (-3500 4750) BN 9
J 2
(-3448 4758);
DISPLAY 0.489362 (-3448 4758);
PAINT MONO (-3448 4758);
FORCEPROP 2 LAST CDS_LIB standard
J 0
(-3450 4750);
DISPLAY INVISIBLE (-3450 4750);
FORCEPROP 2 LAST BOM_COST IO_SLOT
J 0
(-3950 4850);
DISPLAY 0.829787 (-3950 4850);
DISPLAY INVISIBLE (-3950 4850);
FORCEPROP 2 LAST ROOM RISER1
J 0
(-3950 4800);
DISPLAY 0.829787 (-3950 4800);
PAINT RED (-3950 4800);
DISPLAY INVISIBLE (-3950 4800);
FORCEPROP 1 LAST BODY_TYPE PLUMBING
J 2
(-3450 4700);
DISPLAY 0.702128 (-3450 4700);
PAINT GREEN (-3450 4700);
DISPLAY INVISIBLE (-3450 4700);
FORCEPROP 1 LAST HDL_TAP TRUE
J 2
(-3775 4625);
DISPLAY 0.702128 (-3775 4625);
PAINT GREEN (-3775 4625);
DISPLAY INVISIBLE (-3775 4625);
FORCEPROP 1 LAST PATH I170
J 2
(-3448 4750);
DISPLAY 0.872340 (-3448 4750);
PAINT GREEN (-3448 4750);
DISPLAY INVISIBLE (-3448 4750);
FORCEADD TAP..6
R 2
(-3450 4650);
FORCEPROP 3 LASTPIN (-3500 4650) SIG_NAME P5E_CPU1_P2_TX_DP<10>
J 0
(-3490 4660);
DISPLAY 0.659574 (-3490 4660);
PAINT MONO (-3490 4660);
DISPLAY INVISIBLE (-3490 4660);
FORCEPROP 1 LASTPIN (-3500 4650) BN 10
J 2
(-3448 4658);
DISPLAY 0.489362 (-3448 4658);
PAINT MONO (-3448 4658);
FORCEPROP 2 LAST CDS_LIB standard
J 0
(-3450 4650);
DISPLAY INVISIBLE (-3450 4650);
FORCEPROP 2 LAST BOM_COST IO_SLOT
J 0
(-3950 4750);
DISPLAY 0.829787 (-3950 4750);
DISPLAY INVISIBLE (-3950 4750);
FORCEPROP 2 LAST ROOM RISER1
J 0
(-3950 4700);
DISPLAY 0.829787 (-3950 4700);
PAINT RED (-3950 4700);
DISPLAY INVISIBLE (-3950 4700);
FORCEPROP 1 LAST BODY_TYPE PLUMBING
J 2
(-3450 4600);
DISPLAY 0.702128 (-3450 4600);
PAINT GREEN (-3450 4600);
DISPLAY INVISIBLE (-3450 4600);
FORCEPROP 1 LAST HDL_TAP TRUE
J 2
(-3775 4525);
DISPLAY 0.702128 (-3775 4525);
PAINT GREEN (-3775 4525);
DISPLAY INVISIBLE (-3775 4525);
FORCEPROP 1 LAST PATH I171
J 2
(-3448 4650);
DISPLAY 0.872340 (-3448 4650);
PAINT GREEN (-3448 4650);
DISPLAY INVISIBLE (-3448 4650);
FORCEADD TAP..6
R 2
(-3300 4600);
FORCEPROP 3 LASTPIN (-3350 4600) SIG_NAME P5E_CPU1_P2_TX_DN<10>
J 0
(-3340 4610);
DISPLAY 0.659574 (-3340 4610);
PAINT MONO (-3340 4610);
DISPLAY INVISIBLE (-3340 4610);
FORCEPROP 1 LASTPIN (-3350 4600) BN 10
J 2
(-3298 4608);
DISPLAY 0.489362 (-3298 4608);
PAINT MONO (-3298 4608);
FORCEPROP 2 LAST CDS_LIB standard
J 0
(-3300 4600);
DISPLAY INVISIBLE (-3300 4600);
FORCEPROP 2 LAST BOM_COST IO_SLOT
J 0
(-3800 4700);
DISPLAY 0.829787 (-3800 4700);
DISPLAY INVISIBLE (-3800 4700);
FORCEPROP 2 LAST ROOM RISER1
J 0
(-3800 4650);
DISPLAY 0.829787 (-3800 4650);
PAINT RED (-3800 4650);
DISPLAY INVISIBLE (-3800 4650);
FORCEPROP 1 LAST BODY_TYPE PLUMBING
J 2
(-3300 4550);
DISPLAY 0.702128 (-3300 4550);
PAINT GREEN (-3300 4550);
DISPLAY INVISIBLE (-3300 4550);
FORCEPROP 1 LAST HDL_TAP TRUE
J 2
(-3625 4475);
DISPLAY 0.702128 (-3625 4475);
PAINT GREEN (-3625 4475);
DISPLAY INVISIBLE (-3625 4475);
FORCEPROP 1 LAST PATH I172
J 2
(-3298 4600);
DISPLAY 0.872340 (-3298 4600);
PAINT GREEN (-3298 4600);
DISPLAY INVISIBLE (-3298 4600);
FORCEADD TAP..6
R 2
(-3300 4500);
FORCEPROP 3 LASTPIN (-3350 4500) SIG_NAME P5E_CPU1_P2_TX_DN<11>
J 0
(-3340 4510);
DISPLAY 0.659574 (-3340 4510);
PAINT MONO (-3340 4510);
DISPLAY INVISIBLE (-3340 4510);
FORCEPROP 1 LASTPIN (-3350 4500) BN 11
J 2
(-3298 4508);
DISPLAY 0.489362 (-3298 4508);
PAINT MONO (-3298 4508);
FORCEPROP 2 LAST CDS_LIB standard
J 0
(-3300 4500);
DISPLAY INVISIBLE (-3300 4500);
FORCEPROP 2 LAST BOM_COST IO_SLOT
J 0
(-3800 4600);
DISPLAY 0.829787 (-3800 4600);
DISPLAY INVISIBLE (-3800 4600);
FORCEPROP 2 LAST ROOM RISER1
J 0
(-3800 4550);
DISPLAY 0.829787 (-3800 4550);
PAINT RED (-3800 4550);
DISPLAY INVISIBLE (-3800 4550);
FORCEPROP 1 LAST BODY_TYPE PLUMBING
J 2
(-3300 4450);
DISPLAY 0.702128 (-3300 4450);
PAINT GREEN (-3300 4450);
DISPLAY INVISIBLE (-3300 4450);
FORCEPROP 1 LAST HDL_TAP TRUE
J 2
(-3625 4375);
DISPLAY 0.702128 (-3625 4375);
PAINT GREEN (-3625 4375);
DISPLAY INVISIBLE (-3625 4375);
FORCEPROP 1 LAST PATH I173
J 2
(-3298 4500);
DISPLAY 0.872340 (-3298 4500);
PAINT GREEN (-3298 4500);
DISPLAY INVISIBLE (-3298 4500);
FORCEADD TAP..6
R 2
(-3300 4400);
FORCEPROP 3 LASTPIN (-3350 4400) SIG_NAME P5E_CPU1_P2_TX_DN<12>
J 0
(-3340 4410);
DISPLAY 0.659574 (-3340 4410);
PAINT MONO (-3340 4410);
DISPLAY INVISIBLE (-3340 4410);
FORCEPROP 1 LASTPIN (-3350 4400) BN 12
J 2
(-3298 4408);
DISPLAY 0.489362 (-3298 4408);
PAINT MONO (-3298 4408);
FORCEPROP 2 LAST CDS_LIB standard
J 0
(-3300 4400);
DISPLAY INVISIBLE (-3300 4400);
FORCEPROP 2 LAST BOM_COST IO_SLOT
J 0
(-3800 4500);
DISPLAY 0.829787 (-3800 4500);
DISPLAY INVISIBLE (-3800 4500);
FORCEPROP 2 LAST ROOM RISER1
J 0
(-3800 4450);
DISPLAY 0.829787 (-3800 4450);
PAINT RED (-3800 4450);
DISPLAY INVISIBLE (-3800 4450);
FORCEPROP 1 LAST BODY_TYPE PLUMBING
J 2
(-3300 4350);
DISPLAY 0.702128 (-3300 4350);
PAINT GREEN (-3300 4350);
DISPLAY INVISIBLE (-3300 4350);
FORCEPROP 1 LAST HDL_TAP TRUE
J 2
(-3625 4275);
DISPLAY 0.702128 (-3625 4275);
PAINT GREEN (-3625 4275);
DISPLAY INVISIBLE (-3625 4275);
FORCEPROP 1 LAST PATH I174
J 2
(-3298 4400);
DISPLAY 0.872340 (-3298 4400);
PAINT GREEN (-3298 4400);
DISPLAY INVISIBLE (-3298 4400);
FORCEADD TAP..6
R 2
(-3450 4550);
FORCEPROP 3 LASTPIN (-3500 4550) SIG_NAME P5E_CPU1_P2_TX_DP<11>
J 0
(-3490 4560);
DISPLAY 0.659574 (-3490 4560);
PAINT MONO (-3490 4560);
DISPLAY INVISIBLE (-3490 4560);
FORCEPROP 1 LASTPIN (-3500 4550) BN 11
J 2
(-3448 4558);
DISPLAY 0.489362 (-3448 4558);
PAINT MONO (-3448 4558);
FORCEPROP 2 LAST CDS_LIB standard
J 0
(-3450 4550);
DISPLAY INVISIBLE (-3450 4550);
FORCEPROP 2 LAST BOM_COST IO_SLOT
J 0
(-3950 4650);
DISPLAY 0.829787 (-3950 4650);
DISPLAY INVISIBLE (-3950 4650);
FORCEPROP 2 LAST ROOM RISER1
J 0
(-3950 4600);
DISPLAY 0.829787 (-3950 4600);
PAINT RED (-3950 4600);
DISPLAY INVISIBLE (-3950 4600);
FORCEPROP 1 LAST BODY_TYPE PLUMBING
J 2
(-3450 4500);
DISPLAY 0.702128 (-3450 4500);
PAINT GREEN (-3450 4500);
DISPLAY INVISIBLE (-3450 4500);
FORCEPROP 1 LAST HDL_TAP TRUE
J 2
(-3775 4425);
DISPLAY 0.702128 (-3775 4425);
PAINT GREEN (-3775 4425);
DISPLAY INVISIBLE (-3775 4425);
FORCEPROP 1 LAST PATH I175
J 2
(-3448 4550);
DISPLAY 0.872340 (-3448 4550);
PAINT GREEN (-3448 4550);
DISPLAY INVISIBLE (-3448 4550);
FORCEADD TAP..6
R 2
(-3450 4450);
FORCEPROP 3 LASTPIN (-3500 4450) SIG_NAME P5E_CPU1_P2_TX_DP<12>
J 0
(-3490 4460);
DISPLAY 0.659574 (-3490 4460);
PAINT MONO (-3490 4460);
DISPLAY INVISIBLE (-3490 4460);
FORCEPROP 1 LASTPIN (-3500 4450) BN 12
J 2
(-3448 4458);
DISPLAY 0.489362 (-3448 4458);
PAINT MONO (-3448 4458);
FORCEPROP 2 LAST CDS_LIB standard
J 0
(-3450 4450);
DISPLAY INVISIBLE (-3450 4450);
FORCEPROP 2 LAST BOM_COST IO_SLOT
J 0
(-3950 4550);
DISPLAY 0.829787 (-3950 4550);
DISPLAY INVISIBLE (-3950 4550);
FORCEPROP 2 LAST ROOM RISER1
J 0
(-3950 4500);
DISPLAY 0.829787 (-3950 4500);
PAINT RED (-3950 4500);
DISPLAY INVISIBLE (-3950 4500);
FORCEPROP 1 LAST BODY_TYPE PLUMBING
J 2
(-3450 4400);
DISPLAY 0.702128 (-3450 4400);
PAINT GREEN (-3450 4400);
DISPLAY INVISIBLE (-3450 4400);
FORCEPROP 1 LAST HDL_TAP TRUE
J 2
(-3775 4325);
DISPLAY 0.702128 (-3775 4325);
PAINT GREEN (-3775 4325);
DISPLAY INVISIBLE (-3775 4325);
FORCEPROP 1 LAST PATH I176
J 2
(-3448 4450);
DISPLAY 0.872340 (-3448 4450);
PAINT GREEN (-3448 4450);
DISPLAY INVISIBLE (-3448 4450);
FORCEADD TAP..6
R 2
(-3300 4200);
FORCEPROP 3 LASTPIN (-3350 4200) SIG_NAME P5E_CPU1_P2_TX_DN<14>
J 0
(-3340 4210);
DISPLAY 0.659574 (-3340 4210);
PAINT MONO (-3340 4210);
DISPLAY INVISIBLE (-3340 4210);
FORCEPROP 1 LASTPIN (-3350 4200) BN 14
J 2
(-3298 4208);
DISPLAY 0.489362 (-3298 4208);
PAINT MONO (-3298 4208);
FORCEPROP 2 LAST BOM_COST IO_SLOT
J 0
(-3800 4300);
DISPLAY 0.829787 (-3800 4300);
DISPLAY INVISIBLE (-3800 4300);
FORCEPROP 2 LAST CDS_LIB standard
J 0
(-3300 4200);
DISPLAY INVISIBLE (-3300 4200);
FORCEPROP 2 LAST ROOM RISER1
J 0
(-3800 4250);
DISPLAY 0.829787 (-3800 4250);
PAINT RED (-3800 4250);
DISPLAY INVISIBLE (-3800 4250);
FORCEPROP 1 LAST BODY_TYPE PLUMBING
J 2
(-3300 4150);
DISPLAY 0.702128 (-3300 4150);
PAINT GREEN (-3300 4150);
DISPLAY INVISIBLE (-3300 4150);
FORCEPROP 1 LAST HDL_TAP TRUE
J 2
(-3625 4075);
DISPLAY 0.702128 (-3625 4075);
PAINT GREEN (-3625 4075);
DISPLAY INVISIBLE (-3625 4075);
FORCEPROP 1 LAST PATH I177
J 2
(-3298 4200);
DISPLAY 0.872340 (-3298 4200);
PAINT GREEN (-3298 4200);
DISPLAY INVISIBLE (-3298 4200);
FORCEADD TAP..6
R 2
(-3300 4100);
FORCEPROP 3 LASTPIN (-3350 4100) SIG_NAME P5E_CPU1_P2_TX_DN<15>
J 0
(-3340 4110);
DISPLAY 0.659574 (-3340 4110);
PAINT MONO (-3340 4110);
DISPLAY INVISIBLE (-3340 4110);
FORCEPROP 1 LASTPIN (-3350 4100) BN 15
J 2
(-3298 4108);
DISPLAY 0.489362 (-3298 4108);
PAINT MONO (-3298 4108);
FORCEPROP 2 LAST CDS_LIB standard
J 0
(-3300 4100);
DISPLAY INVISIBLE (-3300 4100);
FORCEPROP 2 LAST BOM_COST IO_SLOT
J 0
(-3800 4200);
DISPLAY 0.829787 (-3800 4200);
DISPLAY INVISIBLE (-3800 4200);
FORCEPROP 2 LAST ROOM RISER1
J 0
(-3800 4150);
DISPLAY 0.829787 (-3800 4150);
PAINT RED (-3800 4150);
DISPLAY INVISIBLE (-3800 4150);
FORCEPROP 1 LAST BODY_TYPE PLUMBING
J 2
(-3300 4050);
DISPLAY 0.702128 (-3300 4050);
PAINT GREEN (-3300 4050);
DISPLAY INVISIBLE (-3300 4050);
FORCEPROP 1 LAST HDL_TAP TRUE
J 2
(-3625 3975);
DISPLAY 0.702128 (-3625 3975);
PAINT GREEN (-3625 3975);
DISPLAY INVISIBLE (-3625 3975);
FORCEPROP 1 LAST PATH I178
J 2
(-3298 4100);
DISPLAY 0.872340 (-3298 4100);
PAINT GREEN (-3298 4100);
DISPLAY INVISIBLE (-3298 4100);
FORCEADD TAP..6
R 2
(-3300 4300);
FORCEPROP 3 LASTPIN (-3350 4300) SIG_NAME P5E_CPU1_P2_TX_DN<13>
J 0
(-3340 4310);
DISPLAY 0.659574 (-3340 4310);
PAINT MONO (-3340 4310);
DISPLAY INVISIBLE (-3340 4310);
FORCEPROP 1 LASTPIN (-3350 4300) BN 13
J 2
(-3298 4308);
DISPLAY 0.489362 (-3298 4308);
PAINT MONO (-3298 4308);
FORCEPROP 2 LAST CDS_LIB standard
J 0
(-3300 4300);
DISPLAY INVISIBLE (-3300 4300);
FORCEPROP 2 LAST BOM_COST IO_SLOT
J 0
(-3800 4400);
DISPLAY 0.829787 (-3800 4400);
DISPLAY INVISIBLE (-3800 4400);
FORCEPROP 2 LAST ROOM RISER1
J 0
(-3800 4350);
DISPLAY 0.829787 (-3800 4350);
PAINT RED (-3800 4350);
DISPLAY INVISIBLE (-3800 4350);
FORCEPROP 1 LAST BODY_TYPE PLUMBING
J 2
(-3300 4250);
DISPLAY 0.702128 (-3300 4250);
PAINT GREEN (-3300 4250);
DISPLAY INVISIBLE (-3300 4250);
FORCEPROP 1 LAST HDL_TAP TRUE
J 2
(-3625 4175);
DISPLAY 0.702128 (-3625 4175);
PAINT GREEN (-3625 4175);
DISPLAY INVISIBLE (-3625 4175);
FORCEPROP 1 LAST PATH I179
J 2
(-3298 4300);
DISPLAY 0.872340 (-3298 4300);
PAINT GREEN (-3298 4300);
DISPLAY INVISIBLE (-3298 4300);
FORCEADD TAP..6
R 2
(-3450 4350);
FORCEPROP 3 LASTPIN (-3500 4350) SIG_NAME P5E_CPU1_P2_TX_DP<13>
J 0
(-3490 4360);
DISPLAY 0.659574 (-3490 4360);
PAINT MONO (-3490 4360);
DISPLAY INVISIBLE (-3490 4360);
FORCEPROP 1 LASTPIN (-3500 4350) BN 13
J 2
(-3448 4358);
DISPLAY 0.489362 (-3448 4358);
PAINT MONO (-3448 4358);
FORCEPROP 2 LAST CDS_LIB standard
J 0
(-3450 4350);
DISPLAY INVISIBLE (-3450 4350);
FORCEPROP 2 LAST BOM_COST IO_SLOT
J 0
(-3950 4450);
DISPLAY 0.829787 (-3950 4450);
DISPLAY INVISIBLE (-3950 4450);
FORCEPROP 2 LAST ROOM RISER1
J 0
(-3950 4400);
DISPLAY 0.829787 (-3950 4400);
PAINT RED (-3950 4400);
DISPLAY INVISIBLE (-3950 4400);
FORCEPROP 1 LAST BODY_TYPE PLUMBING
J 2
(-3450 4300);
DISPLAY 0.702128 (-3450 4300);
PAINT GREEN (-3450 4300);
DISPLAY INVISIBLE (-3450 4300);
FORCEPROP 1 LAST HDL_TAP TRUE
J 2
(-3775 4225);
DISPLAY 0.702128 (-3775 4225);
PAINT GREEN (-3775 4225);
DISPLAY INVISIBLE (-3775 4225);
FORCEPROP 1 LAST PATH I180
J 2
(-3448 4350);
DISPLAY 0.872340 (-3448 4350);
PAINT GREEN (-3448 4350);
DISPLAY INVISIBLE (-3448 4350);
FORCEADD TAP..6
R 2
(-3450 4250);
FORCEPROP 3 LASTPIN (-3500 4250) SIG_NAME P5E_CPU1_P2_TX_DP<14>
J 0
(-3490 4260);
DISPLAY 0.659574 (-3490 4260);
PAINT MONO (-3490 4260);
DISPLAY INVISIBLE (-3490 4260);
FORCEPROP 1 LASTPIN (-3500 4250) BN 14
J 2
(-3448 4258);
DISPLAY 0.489362 (-3448 4258);
PAINT MONO (-3448 4258);
FORCEPROP 2 LAST CDS_LIB standard
J 0
(-3450 4250);
DISPLAY INVISIBLE (-3450 4250);
FORCEPROP 2 LAST BOM_COST IO_SLOT
J 0
(-3950 4350);
DISPLAY 0.829787 (-3950 4350);
DISPLAY INVISIBLE (-3950 4350);
FORCEPROP 2 LAST ROOM RISER1
J 0
(-3950 4300);
DISPLAY 0.829787 (-3950 4300);
PAINT RED (-3950 4300);
DISPLAY INVISIBLE (-3950 4300);
FORCEPROP 1 LAST BODY_TYPE PLUMBING
J 2
(-3450 4200);
DISPLAY 0.702128 (-3450 4200);
PAINT GREEN (-3450 4200);
DISPLAY INVISIBLE (-3450 4200);
FORCEPROP 1 LAST HDL_TAP TRUE
J 2
(-3775 4125);
DISPLAY 0.702128 (-3775 4125);
PAINT GREEN (-3775 4125);
DISPLAY INVISIBLE (-3775 4125);
FORCEPROP 1 LAST PATH I181
J 2
(-3448 4250);
DISPLAY 0.872340 (-3448 4250);
PAINT GREEN (-3448 4250);
DISPLAY INVISIBLE (-3448 4250);
FORCEADD TAP..6
R 2
(-3450 4150);
FORCEPROP 3 LASTPIN (-3500 4150) SIG_NAME P5E_CPU1_P2_TX_DP<15>
J 0
(-3490 4160);
DISPLAY 0.659574 (-3490 4160);
PAINT MONO (-3490 4160);
DISPLAY INVISIBLE (-3490 4160);
FORCEPROP 1 LASTPIN (-3500 4150) BN 15
J 2
(-3448 4158);
DISPLAY 0.489362 (-3448 4158);
PAINT MONO (-3448 4158);
FORCEPROP 2 LAST CDS_LIB standard
J 0
(-3450 4150);
DISPLAY INVISIBLE (-3450 4150);
FORCEPROP 2 LAST BOM_COST IO_SLOT
J 0
(-3950 4250);
DISPLAY 0.829787 (-3950 4250);
DISPLAY INVISIBLE (-3950 4250);
FORCEPROP 2 LAST ROOM RISER1
J 0
(-3950 4200);
DISPLAY 0.829787 (-3950 4200);
PAINT RED (-3950 4200);
DISPLAY INVISIBLE (-3950 4200);
FORCEPROP 1 LAST BODY_TYPE PLUMBING
J 2
(-3450 4100);
DISPLAY 0.702128 (-3450 4100);
PAINT GREEN (-3450 4100);
DISPLAY INVISIBLE (-3450 4100);
FORCEPROP 1 LAST HDL_TAP TRUE
J 2
(-3775 4025);
DISPLAY 0.702128 (-3775 4025);
PAINT GREEN (-3775 4025);
DISPLAY INVISIBLE (-3775 4025);
FORCEPROP 1 LAST PATH I182
J 2
(-3448 4150);
DISPLAY 0.872340 (-3448 4150);
PAINT GREEN (-3448 4150);
DISPLAY INVISIBLE (-3448 4150);
FORCEADD OFFPAGE..2
(-2325 3375);
FORCEPROP 2 LAST $XR0 67 
J 0
(-2136 3375);
DISPLAY 0.638298 (-2136 3375);
PAINT MONO (-2136 3375);
FORCEPROP 2 LAST CDS_LIB standard
J 0
(-2325 3375);
DISPLAY INVISIBLE (-2325 3375);
FORCEPROP 1 LAST OFFPAGE TRUE
J 0
(-2000 3250);
DISPLAY 0.872340 (-2000 3250);
PAINT GREEN (-2000 3250);
DISPLAY INVISIBLE (-2000 3250);
FORCEPROP 1 LAST COMMENT_BODY TRUE
J 0
(-2370 3280);
DISPLAY 0.872340 (-2370 3280);
PAINT GREEN (-2370 3280);
DISPLAY INVISIBLE (-2370 3280);
FORCEPROP 2 LAST PATH I183
J 0
(-2025 3425);
DISPLAY 1.021277 (-2025 3425);
DISPLAY INVISIBLE (-2025 3425);
FORCEADD OFFPAGE..2
(-2325 3325);
FORCEPROP 2 LAST $XR0 67 
J 0
(-2136 3325);
DISPLAY 0.638298 (-2136 3325);
PAINT MONO (-2136 3325);
FORCEPROP 2 LAST CDS_LIB standard
J 0
(-2325 3325);
DISPLAY INVISIBLE (-2325 3325);
FORCEPROP 1 LAST OFFPAGE TRUE
J 0
(-2000 3200);
DISPLAY 0.872340 (-2000 3200);
PAINT GREEN (-2000 3200);
DISPLAY INVISIBLE (-2000 3200);
FORCEPROP 1 LAST COMMENT_BODY TRUE
J 0
(-2370 3230);
DISPLAY 0.872340 (-2370 3230);
PAINT GREEN (-2370 3230);
DISPLAY INVISIBLE (-2370 3230);
FORCEPROP 2 LAST PATH I184
J 0
(-2025 3375);
DISPLAY 1.021277 (-2025 3375);
DISPLAY INVISIBLE (-2025 3375);
FORCEADD TAP..6
R 2
(-3300 3100);
FORCEPROP 3 LASTPIN (-3350 3100) SIG_NAME P5E_CPU1_P3_TX_DN<0>
J 0
(-3340 3110);
DISPLAY 0.659574 (-3340 3110);
PAINT MONO (-3340 3110);
DISPLAY INVISIBLE (-3340 3110);
FORCEPROP 1 LASTPIN (-3350 3100) BN 0
J 2
(-3298 3108);
DISPLAY 0.489362 (-3298 3108);
PAINT MONO (-3298 3108);
FORCEPROP 2 LAST CDS_LIB mstr_standard
J 0
(-3300 3100);
DISPLAY INVISIBLE (-3300 3100);
FORCEPROP 2 LAST BOM_COST IO_SLOT
J 0
(-3800 3200);
DISPLAY 0.829787 (-3800 3200);
DISPLAY INVISIBLE (-3800 3200);
FORCEPROP 2 LAST ROOM RISER1
J 0
(-3800 3150);
DISPLAY 0.829787 (-3800 3150);
PAINT RED (-3800 3150);
DISPLAY INVISIBLE (-3800 3150);
FORCEPROP 1 LAST BODY_TYPE PLUMBING
J 2
(-3300 3050);
DISPLAY 0.702128 (-3300 3050);
PAINT GREEN (-3300 3050);
DISPLAY INVISIBLE (-3300 3050);
FORCEPROP 1 LAST HDL_TAP TRUE
J 2
(-3625 2975);
DISPLAY 0.702128 (-3625 2975);
PAINT GREEN (-3625 2975);
DISPLAY INVISIBLE (-3625 2975);
FORCEPROP 1 LAST PATH I185
J 2
(-3298 3100);
DISPLAY 0.872340 (-3298 3100);
PAINT GREEN (-3298 3100);
DISPLAY INVISIBLE (-3298 3100);
FORCEADD TAP..6
R 2
(-3450 3150);
FORCEPROP 3 LASTPIN (-3500 3150) SIG_NAME P5E_CPU1_P3_TX_DP<0>
J 0
(-3490 3160);
DISPLAY 0.659574 (-3490 3160);
PAINT MONO (-3490 3160);
DISPLAY INVISIBLE (-3490 3160);
FORCEPROP 1 LASTPIN (-3500 3150) BN 0
J 2
(-3448 3158);
DISPLAY 0.489362 (-3448 3158);
PAINT MONO (-3448 3158);
FORCEPROP 2 LAST BOM_COST IO_SLOT
J 0
(-3950 3250);
DISPLAY 0.829787 (-3950 3250);
DISPLAY INVISIBLE (-3950 3250);
FORCEPROP 2 LAST CDS_LIB mstr_standard
J 0
(-3450 3150);
DISPLAY INVISIBLE (-3450 3150);
FORCEPROP 2 LAST ROOM RISER1
J 0
(-3950 3200);
DISPLAY 0.829787 (-3950 3200);
PAINT RED (-3950 3200);
DISPLAY INVISIBLE (-3950 3200);
FORCEPROP 1 LAST BODY_TYPE PLUMBING
J 2
(-3450 3100);
DISPLAY 0.702128 (-3450 3100);
PAINT GREEN (-3450 3100);
DISPLAY INVISIBLE (-3450 3100);
FORCEPROP 1 LAST HDL_TAP TRUE
J 2
(-3775 3025);
DISPLAY 0.702128 (-3775 3025);
PAINT GREEN (-3775 3025);
DISPLAY INVISIBLE (-3775 3025);
FORCEPROP 1 LAST PATH I186
J 2
(-3448 3150);
DISPLAY 0.872340 (-3448 3150);
PAINT GREEN (-3448 3150);
DISPLAY INVISIBLE (-3448 3150);
FORCEADD TAP..6
R 2
(-3300 2900);
FORCEPROP 3 LASTPIN (-3350 2900) SIG_NAME P5E_CPU1_P3_TX_DN<2>
J 0
(-3340 2910);
DISPLAY 0.659574 (-3340 2910);
PAINT MONO (-3340 2910);
DISPLAY INVISIBLE (-3340 2910);
FORCEPROP 1 LASTPIN (-3350 2900) BN 2
J 2
(-3298 2908);
DISPLAY 0.489362 (-3298 2908);
PAINT MONO (-3298 2908);
FORCEPROP 2 LAST BOM_COST IO_SLOT
J 0
(-3800 3000);
DISPLAY 0.829787 (-3800 3000);
DISPLAY INVISIBLE (-3800 3000);
FORCEPROP 2 LAST CDS_LIB standard
J 0
(-3300 2900);
DISPLAY INVISIBLE (-3300 2900);
FORCEPROP 2 LAST ROOM RISER1
J 0
(-3800 2950);
DISPLAY 0.829787 (-3800 2950);
PAINT RED (-3800 2950);
DISPLAY INVISIBLE (-3800 2950);
FORCEPROP 1 LAST BODY_TYPE PLUMBING
J 2
(-3300 2850);
DISPLAY 0.702128 (-3300 2850);
PAINT GREEN (-3300 2850);
DISPLAY INVISIBLE (-3300 2850);
FORCEPROP 1 LAST HDL_TAP TRUE
J 2
(-3625 2775);
DISPLAY 0.702128 (-3625 2775);
PAINT GREEN (-3625 2775);
DISPLAY INVISIBLE (-3625 2775);
FORCEPROP 1 LAST PATH I187
J 2
(-3298 2900);
DISPLAY 0.872340 (-3298 2900);
PAINT GREEN (-3298 2900);
DISPLAY INVISIBLE (-3298 2900);
FORCEADD TAP..6
R 2
(-3300 3000);
FORCEPROP 3 LASTPIN (-3350 3000) SIG_NAME P5E_CPU1_P3_TX_DN<1>
J 0
(-3340 3010);
DISPLAY 0.659574 (-3340 3010);
PAINT MONO (-3340 3010);
DISPLAY INVISIBLE (-3340 3010);
FORCEPROP 1 LASTPIN (-3350 3000) BN 1
J 2
(-3298 3008);
DISPLAY 0.489362 (-3298 3008);
PAINT MONO (-3298 3008);
FORCEPROP 2 LAST BOM_COST IO_SLOT
J 0
(-3800 3100);
DISPLAY 0.829787 (-3800 3100);
DISPLAY INVISIBLE (-3800 3100);
FORCEPROP 2 LAST CDS_LIB mstr_standard
J 0
(-3300 3000);
DISPLAY INVISIBLE (-3300 3000);
FORCEPROP 2 LAST ROOM RISER1
J 0
(-3800 3050);
DISPLAY 0.829787 (-3800 3050);
PAINT RED (-3800 3050);
DISPLAY INVISIBLE (-3800 3050);
FORCEPROP 1 LAST BODY_TYPE PLUMBING
J 2
(-3300 2950);
DISPLAY 0.702128 (-3300 2950);
PAINT GREEN (-3300 2950);
DISPLAY INVISIBLE (-3300 2950);
FORCEPROP 1 LAST HDL_TAP TRUE
J 2
(-3625 2875);
DISPLAY 0.702128 (-3625 2875);
PAINT GREEN (-3625 2875);
DISPLAY INVISIBLE (-3625 2875);
FORCEPROP 1 LAST PATH I188
J 2
(-3298 3000);
DISPLAY 0.872340 (-3298 3000);
PAINT GREEN (-3298 3000);
DISPLAY INVISIBLE (-3298 3000);
FORCEADD TAP..6
R 2
(-3450 3050);
FORCEPROP 3 LASTPIN (-3500 3050) SIG_NAME P5E_CPU1_P3_TX_DP<1>
J 0
(-3490 3060);
DISPLAY 0.659574 (-3490 3060);
PAINT MONO (-3490 3060);
DISPLAY INVISIBLE (-3490 3060);
FORCEPROP 1 LASTPIN (-3500 3050) BN 1
J 2
(-3448 3058);
DISPLAY 0.489362 (-3448 3058);
PAINT MONO (-3448 3058);
FORCEPROP 2 LAST BOM_COST IO_SLOT
J 0
(-3950 3150);
DISPLAY 0.829787 (-3950 3150);
DISPLAY INVISIBLE (-3950 3150);
FORCEPROP 2 LAST CDS_LIB mstr_standard
J 0
(-3450 3050);
DISPLAY INVISIBLE (-3450 3050);
FORCEPROP 2 LAST ROOM RISER1
J 0
(-3950 3100);
DISPLAY 0.829787 (-3950 3100);
PAINT RED (-3950 3100);
DISPLAY INVISIBLE (-3950 3100);
FORCEPROP 1 LAST BODY_TYPE PLUMBING
J 2
(-3450 3000);
DISPLAY 0.702128 (-3450 3000);
PAINT GREEN (-3450 3000);
DISPLAY INVISIBLE (-3450 3000);
FORCEPROP 1 LAST HDL_TAP TRUE
J 2
(-3775 2925);
DISPLAY 0.702128 (-3775 2925);
PAINT GREEN (-3775 2925);
DISPLAY INVISIBLE (-3775 2925);
FORCEPROP 1 LAST PATH I189
J 2
(-3448 3050);
DISPLAY 0.872340 (-3448 3050);
PAINT GREEN (-3448 3050);
DISPLAY INVISIBLE (-3448 3050);
FORCEADD TAP..6
R 2
(-3450 2950);
FORCEPROP 3 LASTPIN (-3500 2950) SIG_NAME P5E_CPU1_P3_TX_DP<2>
J 0
(-3490 2960);
DISPLAY 0.659574 (-3490 2960);
PAINT MONO (-3490 2960);
DISPLAY INVISIBLE (-3490 2960);
FORCEPROP 1 LASTPIN (-3500 2950) BN 2
J 2
(-3448 2958);
DISPLAY 0.489362 (-3448 2958);
PAINT MONO (-3448 2958);
FORCEPROP 2 LAST BOM_COST IO_SLOT
J 0
(-3950 3050);
DISPLAY 0.829787 (-3950 3050);
DISPLAY INVISIBLE (-3950 3050);
FORCEPROP 2 LAST CDS_LIB standard
J 0
(-3450 2950);
DISPLAY INVISIBLE (-3450 2950);
FORCEPROP 2 LAST ROOM RISER1
J 0
(-3950 3000);
DISPLAY 0.829787 (-3950 3000);
PAINT RED (-3950 3000);
DISPLAY INVISIBLE (-3950 3000);
FORCEPROP 1 LAST BODY_TYPE PLUMBING
J 2
(-3450 2900);
DISPLAY 0.702128 (-3450 2900);
PAINT GREEN (-3450 2900);
DISPLAY INVISIBLE (-3450 2900);
FORCEPROP 1 LAST HDL_TAP TRUE
J 2
(-3775 2825);
DISPLAY 0.702128 (-3775 2825);
PAINT GREEN (-3775 2825);
DISPLAY INVISIBLE (-3775 2825);
FORCEPROP 1 LAST PATH I190
J 2
(-3448 2950);
DISPLAY 0.872340 (-3448 2950);
PAINT GREEN (-3448 2950);
DISPLAY INVISIBLE (-3448 2950);
FORCEADD TAP..6
R 2
(-3450 2850);
FORCEPROP 3 LASTPIN (-3500 2850) SIG_NAME P5E_CPU1_P3_TX_DP<3>
J 0
(-3490 2860);
DISPLAY 0.659574 (-3490 2860);
PAINT MONO (-3490 2860);
DISPLAY INVISIBLE (-3490 2860);
FORCEPROP 1 LASTPIN (-3500 2850) BN 3
J 2
(-3448 2858);
DISPLAY 0.489362 (-3448 2858);
PAINT MONO (-3448 2858);
FORCEPROP 2 LAST BOM_COST IO_SLOT
J 0
(-3950 2950);
DISPLAY 0.829787 (-3950 2950);
DISPLAY INVISIBLE (-3950 2950);
FORCEPROP 2 LAST CDS_LIB standard
J 0
(-3450 2850);
DISPLAY INVISIBLE (-3450 2850);
FORCEPROP 2 LAST ROOM RISER1
J 0
(-3950 2900);
DISPLAY 0.829787 (-3950 2900);
PAINT RED (-3950 2900);
DISPLAY INVISIBLE (-3950 2900);
FORCEPROP 1 LAST BODY_TYPE PLUMBING
J 2
(-3450 2800);
DISPLAY 0.702128 (-3450 2800);
PAINT GREEN (-3450 2800);
DISPLAY INVISIBLE (-3450 2800);
FORCEPROP 1 LAST HDL_TAP TRUE
J 2
(-3775 2725);
DISPLAY 0.702128 (-3775 2725);
PAINT GREEN (-3775 2725);
DISPLAY INVISIBLE (-3775 2725);
FORCEPROP 1 LAST PATH I191
J 2
(-3448 2850);
DISPLAY 0.872340 (-3448 2850);
PAINT GREEN (-3448 2850);
DISPLAY INVISIBLE (-3448 2850);
FORCEADD TAP..6
R 2
(-3300 2800);
FORCEPROP 3 LASTPIN (-3350 2800) SIG_NAME P5E_CPU1_P3_TX_DN<3>
J 0
(-3340 2810);
DISPLAY 0.659574 (-3340 2810);
PAINT MONO (-3340 2810);
DISPLAY INVISIBLE (-3340 2810);
FORCEPROP 1 LASTPIN (-3350 2800) BN 3
J 2
(-3298 2808);
DISPLAY 0.489362 (-3298 2808);
PAINT MONO (-3298 2808);
FORCEPROP 2 LAST BOM_COST IO_SLOT
J 0
(-3800 2900);
DISPLAY 0.829787 (-3800 2900);
DISPLAY INVISIBLE (-3800 2900);
FORCEPROP 2 LAST CDS_LIB standard
J 0
(-3300 2800);
DISPLAY INVISIBLE (-3300 2800);
FORCEPROP 2 LAST ROOM RISER1
J 0
(-3800 2850);
DISPLAY 0.829787 (-3800 2850);
PAINT RED (-3800 2850);
DISPLAY INVISIBLE (-3800 2850);
FORCEPROP 1 LAST BODY_TYPE PLUMBING
J 2
(-3300 2750);
DISPLAY 0.702128 (-3300 2750);
PAINT GREEN (-3300 2750);
DISPLAY INVISIBLE (-3300 2750);
FORCEPROP 1 LAST HDL_TAP TRUE
J 2
(-3625 2675);
DISPLAY 0.702128 (-3625 2675);
PAINT GREEN (-3625 2675);
DISPLAY INVISIBLE (-3625 2675);
FORCEPROP 1 LAST PATH I192
J 2
(-3298 2800);
DISPLAY 0.872340 (-3298 2800);
PAINT GREEN (-3298 2800);
DISPLAY INVISIBLE (-3298 2800);
FORCEADD TAP..6
R 2
(-3300 2700);
FORCEPROP 3 LASTPIN (-3350 2700) SIG_NAME P5E_CPU1_P3_TX_DN<4>
J 0
(-3340 2710);
DISPLAY 0.659574 (-3340 2710);
PAINT MONO (-3340 2710);
DISPLAY INVISIBLE (-3340 2710);
FORCEPROP 1 LASTPIN (-3350 2700) BN 4
J 2
(-3298 2708);
DISPLAY 0.489362 (-3298 2708);
PAINT MONO (-3298 2708);
FORCEPROP 2 LAST BOM_COST IO_SLOT
J 0
(-3800 2800);
DISPLAY 0.829787 (-3800 2800);
DISPLAY INVISIBLE (-3800 2800);
FORCEPROP 2 LAST CDS_LIB standard
J 0
(-3300 2700);
DISPLAY INVISIBLE (-3300 2700);
FORCEPROP 2 LAST ROOM RISER1
J 0
(-3800 2750);
DISPLAY 0.829787 (-3800 2750);
PAINT RED (-3800 2750);
DISPLAY INVISIBLE (-3800 2750);
FORCEPROP 1 LAST BODY_TYPE PLUMBING
J 2
(-3300 2650);
DISPLAY 0.702128 (-3300 2650);
PAINT GREEN (-3300 2650);
DISPLAY INVISIBLE (-3300 2650);
FORCEPROP 1 LAST HDL_TAP TRUE
J 2
(-3625 2575);
DISPLAY 0.702128 (-3625 2575);
PAINT GREEN (-3625 2575);
DISPLAY INVISIBLE (-3625 2575);
FORCEPROP 1 LAST PATH I193
J 2
(-3298 2700);
DISPLAY 0.872340 (-3298 2700);
PAINT GREEN (-3298 2700);
DISPLAY INVISIBLE (-3298 2700);
FORCEADD TAP..6
R 2
(-3300 2600);
FORCEPROP 3 LASTPIN (-3350 2600) SIG_NAME P5E_CPU1_P3_TX_DN<5>
J 0
(-3340 2610);
DISPLAY 0.659574 (-3340 2610);
PAINT MONO (-3340 2610);
DISPLAY INVISIBLE (-3340 2610);
FORCEPROP 1 LASTPIN (-3350 2600) BN 5
J 2
(-3298 2608);
DISPLAY 0.489362 (-3298 2608);
PAINT MONO (-3298 2608);
FORCEPROP 2 LAST BOM_COST IO_SLOT
J 0
(-3800 2700);
DISPLAY 0.829787 (-3800 2700);
DISPLAY INVISIBLE (-3800 2700);
FORCEPROP 2 LAST CDS_LIB standard
J 0
(-3300 2600);
DISPLAY INVISIBLE (-3300 2600);
FORCEPROP 2 LAST ROOM RISER1
J 0
(-3800 2650);
DISPLAY 0.829787 (-3800 2650);
PAINT RED (-3800 2650);
DISPLAY INVISIBLE (-3800 2650);
FORCEPROP 1 LAST BODY_TYPE PLUMBING
J 2
(-3300 2550);
DISPLAY 0.702128 (-3300 2550);
PAINT GREEN (-3300 2550);
DISPLAY INVISIBLE (-3300 2550);
FORCEPROP 1 LAST HDL_TAP TRUE
J 2
(-3625 2475);
DISPLAY 0.702128 (-3625 2475);
PAINT GREEN (-3625 2475);
DISPLAY INVISIBLE (-3625 2475);
FORCEPROP 1 LAST PATH I194
J 2
(-3298 2600);
DISPLAY 0.872340 (-3298 2600);
PAINT GREEN (-3298 2600);
DISPLAY INVISIBLE (-3298 2600);
FORCEADD TAP..6
R 2
(-3450 2750);
FORCEPROP 3 LASTPIN (-3500 2750) SIG_NAME P5E_CPU1_P3_TX_DP<4>
J 0
(-3490 2760);
DISPLAY 0.659574 (-3490 2760);
PAINT MONO (-3490 2760);
DISPLAY INVISIBLE (-3490 2760);
FORCEPROP 1 LASTPIN (-3500 2750) BN 4
J 2
(-3448 2758);
DISPLAY 0.489362 (-3448 2758);
PAINT MONO (-3448 2758);
FORCEPROP 2 LAST BOM_COST IO_SLOT
J 0
(-3950 2850);
DISPLAY 0.829787 (-3950 2850);
DISPLAY INVISIBLE (-3950 2850);
FORCEPROP 2 LAST CDS_LIB standard
J 0
(-3450 2750);
DISPLAY INVISIBLE (-3450 2750);
FORCEPROP 2 LAST ROOM RISER1
J 0
(-3950 2800);
DISPLAY 0.829787 (-3950 2800);
PAINT RED (-3950 2800);
DISPLAY INVISIBLE (-3950 2800);
FORCEPROP 1 LAST BODY_TYPE PLUMBING
J 2
(-3450 2700);
DISPLAY 0.702128 (-3450 2700);
PAINT GREEN (-3450 2700);
DISPLAY INVISIBLE (-3450 2700);
FORCEPROP 1 LAST HDL_TAP TRUE
J 2
(-3775 2625);
DISPLAY 0.702128 (-3775 2625);
PAINT GREEN (-3775 2625);
DISPLAY INVISIBLE (-3775 2625);
FORCEPROP 1 LAST PATH I195
J 2
(-3448 2750);
DISPLAY 0.872340 (-3448 2750);
PAINT GREEN (-3448 2750);
DISPLAY INVISIBLE (-3448 2750);
FORCEADD TAP..6
R 2
(-3450 2650);
FORCEPROP 3 LASTPIN (-3500 2650) SIG_NAME P5E_CPU1_P3_TX_DP<5>
J 0
(-3490 2660);
DISPLAY 0.659574 (-3490 2660);
PAINT MONO (-3490 2660);
DISPLAY INVISIBLE (-3490 2660);
FORCEPROP 1 LASTPIN (-3500 2650) BN 5
J 2
(-3448 2658);
DISPLAY 0.489362 (-3448 2658);
PAINT MONO (-3448 2658);
FORCEPROP 2 LAST BOM_COST IO_SLOT
J 0
(-3950 2750);
DISPLAY 0.829787 (-3950 2750);
DISPLAY INVISIBLE (-3950 2750);
FORCEPROP 2 LAST CDS_LIB standard
J 0
(-3450 2650);
DISPLAY INVISIBLE (-3450 2650);
FORCEPROP 2 LAST ROOM RISER1
J 0
(-3950 2700);
DISPLAY 0.829787 (-3950 2700);
PAINT RED (-3950 2700);
DISPLAY INVISIBLE (-3950 2700);
FORCEPROP 1 LAST BODY_TYPE PLUMBING
J 2
(-3450 2600);
DISPLAY 0.702128 (-3450 2600);
PAINT GREEN (-3450 2600);
DISPLAY INVISIBLE (-3450 2600);
FORCEPROP 1 LAST HDL_TAP TRUE
J 2
(-3775 2525);
DISPLAY 0.702128 (-3775 2525);
PAINT GREEN (-3775 2525);
DISPLAY INVISIBLE (-3775 2525);
FORCEPROP 1 LAST PATH I196
J 2
(-3448 2650);
DISPLAY 0.872340 (-3448 2650);
PAINT GREEN (-3448 2650);
DISPLAY INVISIBLE (-3448 2650);
FORCEADD TAP..6
R 2
(-3300 2400);
FORCEPROP 3 LASTPIN (-3350 2400) SIG_NAME P5E_CPU1_P3_TX_DN<7>
J 0
(-3340 2410);
DISPLAY 0.659574 (-3340 2410);
PAINT MONO (-3340 2410);
DISPLAY INVISIBLE (-3340 2410);
FORCEPROP 1 LASTPIN (-3350 2400) BN 7
J 2
(-3298 2408);
DISPLAY 0.489362 (-3298 2408);
PAINT MONO (-3298 2408);
FORCEPROP 2 LAST BOM_COST IO_SLOT
J 0
(-3800 2500);
DISPLAY 0.829787 (-3800 2500);
DISPLAY INVISIBLE (-3800 2500);
FORCEPROP 2 LAST CDS_LIB standard
J 0
(-3300 2400);
DISPLAY INVISIBLE (-3300 2400);
FORCEPROP 2 LAST ROOM RISER1
J 0
(-3800 2450);
DISPLAY 0.829787 (-3800 2450);
PAINT RED (-3800 2450);
DISPLAY INVISIBLE (-3800 2450);
FORCEPROP 1 LAST BODY_TYPE PLUMBING
J 2
(-3300 2350);
DISPLAY 0.702128 (-3300 2350);
PAINT GREEN (-3300 2350);
DISPLAY INVISIBLE (-3300 2350);
FORCEPROP 1 LAST HDL_TAP TRUE
J 2
(-3625 2275);
DISPLAY 0.702128 (-3625 2275);
PAINT GREEN (-3625 2275);
DISPLAY INVISIBLE (-3625 2275);
FORCEPROP 1 LAST PATH I197
J 2
(-3298 2400);
DISPLAY 0.872340 (-3298 2400);
PAINT GREEN (-3298 2400);
DISPLAY INVISIBLE (-3298 2400);
FORCEADD TAP..6
R 2
(-3300 2500);
FORCEPROP 3 LASTPIN (-3350 2500) SIG_NAME P5E_CPU1_P3_TX_DN<6>
J 0
(-3340 2510);
DISPLAY 0.659574 (-3340 2510);
PAINT MONO (-3340 2510);
DISPLAY INVISIBLE (-3340 2510);
FORCEPROP 1 LASTPIN (-3350 2500) BN 6
J 2
(-3298 2508);
DISPLAY 0.489362 (-3298 2508);
PAINT MONO (-3298 2508);
FORCEPROP 2 LAST BOM_COST IO_SLOT
J 0
(-3800 2600);
DISPLAY 0.829787 (-3800 2600);
DISPLAY INVISIBLE (-3800 2600);
FORCEPROP 2 LAST CDS_LIB standard
J 0
(-3300 2500);
DISPLAY INVISIBLE (-3300 2500);
FORCEPROP 2 LAST ROOM RISER1
J 0
(-3800 2550);
DISPLAY 0.829787 (-3800 2550);
PAINT RED (-3800 2550);
DISPLAY INVISIBLE (-3800 2550);
FORCEPROP 1 LAST BODY_TYPE PLUMBING
J 2
(-3300 2450);
DISPLAY 0.702128 (-3300 2450);
PAINT GREEN (-3300 2450);
DISPLAY INVISIBLE (-3300 2450);
FORCEPROP 1 LAST HDL_TAP TRUE
J 2
(-3625 2375);
DISPLAY 0.702128 (-3625 2375);
PAINT GREEN (-3625 2375);
DISPLAY INVISIBLE (-3625 2375);
FORCEPROP 1 LAST PATH I198
J 2
(-3298 2500);
DISPLAY 0.872340 (-3298 2500);
PAINT GREEN (-3298 2500);
DISPLAY INVISIBLE (-3298 2500);
FORCEADD TAP..6
R 2
(-3450 2550);
FORCEPROP 3 LASTPIN (-3500 2550) SIG_NAME P5E_CPU1_P3_TX_DP<6>
J 0
(-3490 2560);
DISPLAY 0.659574 (-3490 2560);
PAINT MONO (-3490 2560);
DISPLAY INVISIBLE (-3490 2560);
FORCEPROP 1 LASTPIN (-3500 2550) BN 6
J 2
(-3448 2558);
DISPLAY 0.489362 (-3448 2558);
PAINT MONO (-3448 2558);
FORCEPROP 2 LAST BOM_COST IO_SLOT
J 0
(-3950 2650);
DISPLAY 0.829787 (-3950 2650);
DISPLAY INVISIBLE (-3950 2650);
FORCEPROP 2 LAST CDS_LIB standard
J 0
(-3450 2550);
DISPLAY INVISIBLE (-3450 2550);
FORCEPROP 2 LAST ROOM RISER1
J 0
(-3950 2600);
DISPLAY 0.829787 (-3950 2600);
PAINT RED (-3950 2600);
DISPLAY INVISIBLE (-3950 2600);
FORCEPROP 1 LAST BODY_TYPE PLUMBING
J 2
(-3450 2500);
DISPLAY 0.702128 (-3450 2500);
PAINT GREEN (-3450 2500);
DISPLAY INVISIBLE (-3450 2500);
FORCEPROP 1 LAST HDL_TAP TRUE
J 2
(-3775 2425);
DISPLAY 0.702128 (-3775 2425);
PAINT GREEN (-3775 2425);
DISPLAY INVISIBLE (-3775 2425);
FORCEPROP 1 LAST PATH I199
J 2
(-3448 2550);
DISPLAY 0.872340 (-3448 2550);
PAINT GREEN (-3448 2550);
DISPLAY INVISIBLE (-3448 2550);
FORCEADD TAP..6
R 2
(-3450 2450);
FORCEPROP 3 LASTPIN (-3500 2450) SIG_NAME P5E_CPU1_P3_TX_DP<7>
J 0
(-3490 2460);
DISPLAY 0.659574 (-3490 2460);
PAINT MONO (-3490 2460);
DISPLAY INVISIBLE (-3490 2460);
FORCEPROP 1 LASTPIN (-3500 2450) BN 7
J 2
(-3448 2458);
DISPLAY 0.489362 (-3448 2458);
PAINT MONO (-3448 2458);
FORCEPROP 2 LAST BOM_COST IO_SLOT
J 0
(-3950 2550);
DISPLAY 0.829787 (-3950 2550);
DISPLAY INVISIBLE (-3950 2550);
FORCEPROP 2 LAST CDS_LIB standard
J 0
(-3450 2450);
DISPLAY INVISIBLE (-3450 2450);
FORCEPROP 2 LAST ROOM RISER1
J 0
(-3950 2500);
DISPLAY 0.829787 (-3950 2500);
PAINT RED (-3950 2500);
DISPLAY INVISIBLE (-3950 2500);
FORCEPROP 1 LAST BODY_TYPE PLUMBING
J 2
(-3450 2400);
DISPLAY 0.702128 (-3450 2400);
PAINT GREEN (-3450 2400);
DISPLAY INVISIBLE (-3450 2400);
FORCEPROP 1 LAST HDL_TAP TRUE
J 2
(-3775 2325);
DISPLAY 0.702128 (-3775 2325);
PAINT GREEN (-3775 2325);
DISPLAY INVISIBLE (-3775 2325);
FORCEPROP 1 LAST PATH I200
J 2
(-3448 2450);
DISPLAY 0.872340 (-3448 2450);
PAINT GREEN (-3448 2450);
DISPLAY INVISIBLE (-3448 2450);
FORCEADD TAP..6
R 2
(-3450 2350);
FORCEPROP 3 LASTPIN (-3500 2350) SIG_NAME P5E_CPU1_P3_TX_DP<8>
J 0
(-3490 2360);
DISPLAY 0.659574 (-3490 2360);
PAINT MONO (-3490 2360);
DISPLAY INVISIBLE (-3490 2360);
FORCEPROP 1 LASTPIN (-3500 2350) BN 8
J 2
(-3448 2358);
DISPLAY 0.489362 (-3448 2358);
PAINT MONO (-3448 2358);
FORCEPROP 2 LAST BOM_COST IO_SLOT
J 0
(-3950 2450);
DISPLAY 0.829787 (-3950 2450);
DISPLAY INVISIBLE (-3950 2450);
FORCEPROP 2 LAST CDS_LIB standard
J 0
(-3450 2350);
DISPLAY INVISIBLE (-3450 2350);
FORCEPROP 2 LAST ROOM RISER1
J 0
(-3950 2400);
DISPLAY 0.829787 (-3950 2400);
PAINT RED (-3950 2400);
DISPLAY INVISIBLE (-3950 2400);
FORCEPROP 1 LAST BODY_TYPE PLUMBING
J 2
(-3450 2300);
DISPLAY 0.702128 (-3450 2300);
PAINT GREEN (-3450 2300);
DISPLAY INVISIBLE (-3450 2300);
FORCEPROP 1 LAST HDL_TAP TRUE
J 2
(-3775 2225);
DISPLAY 0.702128 (-3775 2225);
PAINT GREEN (-3775 2225);
DISPLAY INVISIBLE (-3775 2225);
FORCEPROP 1 LAST PATH I201
J 2
(-3448 2350);
DISPLAY 0.872340 (-3448 2350);
PAINT GREEN (-3448 2350);
DISPLAY INVISIBLE (-3448 2350);
FORCEADD TAP..6
R 2
(-3300 2300);
FORCEPROP 3 LASTPIN (-3350 2300) SIG_NAME P5E_CPU1_P3_TX_DN<8>
J 0
(-3340 2310);
DISPLAY 0.659574 (-3340 2310);
PAINT MONO (-3340 2310);
DISPLAY INVISIBLE (-3340 2310);
FORCEPROP 1 LASTPIN (-3350 2300) BN 8
J 2
(-3298 2308);
DISPLAY 0.489362 (-3298 2308);
PAINT MONO (-3298 2308);
FORCEPROP 2 LAST BOM_COST IO_SLOT
J 0
(-3800 2400);
DISPLAY 0.829787 (-3800 2400);
DISPLAY INVISIBLE (-3800 2400);
FORCEPROP 2 LAST CDS_LIB standard
J 0
(-3300 2300);
DISPLAY INVISIBLE (-3300 2300);
FORCEPROP 2 LAST ROOM RISER1
J 0
(-3800 2350);
DISPLAY 0.829787 (-3800 2350);
PAINT RED (-3800 2350);
DISPLAY INVISIBLE (-3800 2350);
FORCEPROP 1 LAST BODY_TYPE PLUMBING
J 2
(-3300 2250);
DISPLAY 0.702128 (-3300 2250);
PAINT GREEN (-3300 2250);
DISPLAY INVISIBLE (-3300 2250);
FORCEPROP 1 LAST HDL_TAP TRUE
J 2
(-3625 2175);
DISPLAY 0.702128 (-3625 2175);
PAINT GREEN (-3625 2175);
DISPLAY INVISIBLE (-3625 2175);
FORCEPROP 1 LAST PATH I202
J 2
(-3298 2300);
DISPLAY 0.872340 (-3298 2300);
PAINT GREEN (-3298 2300);
DISPLAY INVISIBLE (-3298 2300);
FORCEADD TAP..6
R 2
(-3300 2200);
FORCEPROP 3 LASTPIN (-3350 2200) SIG_NAME P5E_CPU1_P3_TX_DN<9>
J 0
(-3340 2210);
DISPLAY 0.659574 (-3340 2210);
PAINT MONO (-3340 2210);
DISPLAY INVISIBLE (-3340 2210);
FORCEPROP 1 LASTPIN (-3350 2200) BN 9
J 2
(-3298 2208);
DISPLAY 0.489362 (-3298 2208);
PAINT MONO (-3298 2208);
FORCEPROP 2 LAST BOM_COST IO_SLOT
J 0
(-3800 2300);
DISPLAY 0.829787 (-3800 2300);
DISPLAY INVISIBLE (-3800 2300);
FORCEPROP 2 LAST CDS_LIB standard
J 0
(-3300 2200);
DISPLAY INVISIBLE (-3300 2200);
FORCEPROP 2 LAST ROOM RISER1
J 0
(-3800 2250);
DISPLAY 0.829787 (-3800 2250);
PAINT RED (-3800 2250);
DISPLAY INVISIBLE (-3800 2250);
FORCEPROP 1 LAST BODY_TYPE PLUMBING
J 2
(-3300 2150);
DISPLAY 0.702128 (-3300 2150);
PAINT GREEN (-3300 2150);
DISPLAY INVISIBLE (-3300 2150);
FORCEPROP 1 LAST HDL_TAP TRUE
J 2
(-3625 2075);
DISPLAY 0.702128 (-3625 2075);
PAINT GREEN (-3625 2075);
DISPLAY INVISIBLE (-3625 2075);
FORCEPROP 1 LAST PATH I203
J 2
(-3298 2200);
DISPLAY 0.872340 (-3298 2200);
PAINT GREEN (-3298 2200);
DISPLAY INVISIBLE (-3298 2200);
FORCEADD TAP..6
R 2
(-3300 2100);
FORCEPROP 3 LASTPIN (-3350 2100) SIG_NAME P5E_CPU1_P3_TX_DN<10>
J 0
(-3340 2110);
DISPLAY 0.659574 (-3340 2110);
PAINT MONO (-3340 2110);
DISPLAY INVISIBLE (-3340 2110);
FORCEPROP 1 LASTPIN (-3350 2100) BN 10
J 2
(-3298 2108);
DISPLAY 0.489362 (-3298 2108);
PAINT MONO (-3298 2108);
FORCEPROP 2 LAST BOM_COST IO_SLOT
J 0
(-3800 2200);
DISPLAY 0.829787 (-3800 2200);
DISPLAY INVISIBLE (-3800 2200);
FORCEPROP 2 LAST CDS_LIB standard
J 0
(-3300 2100);
DISPLAY INVISIBLE (-3300 2100);
FORCEPROP 2 LAST ROOM RISER1
J 0
(-3800 2150);
DISPLAY 0.829787 (-3800 2150);
PAINT RED (-3800 2150);
DISPLAY INVISIBLE (-3800 2150);
FORCEPROP 1 LAST BODY_TYPE PLUMBING
J 2
(-3300 2050);
DISPLAY 0.702128 (-3300 2050);
PAINT GREEN (-3300 2050);
DISPLAY INVISIBLE (-3300 2050);
FORCEPROP 1 LAST HDL_TAP TRUE
J 2
(-3625 1975);
DISPLAY 0.702128 (-3625 1975);
PAINT GREEN (-3625 1975);
DISPLAY INVISIBLE (-3625 1975);
FORCEPROP 1 LAST PATH I204
J 2
(-3298 2100);
DISPLAY 0.872340 (-3298 2100);
PAINT GREEN (-3298 2100);
DISPLAY INVISIBLE (-3298 2100);
FORCEADD TAP..6
R 2
(-3450 2250);
FORCEPROP 3 LASTPIN (-3500 2250) SIG_NAME P5E_CPU1_P3_TX_DP<9>
J 0
(-3490 2260);
DISPLAY 0.659574 (-3490 2260);
PAINT MONO (-3490 2260);
DISPLAY INVISIBLE (-3490 2260);
FORCEPROP 1 LASTPIN (-3500 2250) BN 9
J 2
(-3448 2258);
DISPLAY 0.489362 (-3448 2258);
PAINT MONO (-3448 2258);
FORCEPROP 2 LAST BOM_COST IO_SLOT
J 0
(-3950 2350);
DISPLAY 0.829787 (-3950 2350);
DISPLAY INVISIBLE (-3950 2350);
FORCEPROP 2 LAST CDS_LIB standard
J 0
(-3450 2250);
DISPLAY INVISIBLE (-3450 2250);
FORCEPROP 2 LAST ROOM RISER1
J 0
(-3950 2300);
DISPLAY 0.829787 (-3950 2300);
PAINT RED (-3950 2300);
DISPLAY INVISIBLE (-3950 2300);
FORCEPROP 1 LAST BODY_TYPE PLUMBING
J 2
(-3450 2200);
DISPLAY 0.702128 (-3450 2200);
PAINT GREEN (-3450 2200);
DISPLAY INVISIBLE (-3450 2200);
FORCEPROP 1 LAST HDL_TAP TRUE
J 2
(-3775 2125);
DISPLAY 0.702128 (-3775 2125);
PAINT GREEN (-3775 2125);
DISPLAY INVISIBLE (-3775 2125);
FORCEPROP 1 LAST PATH I205
J 2
(-3448 2250);
DISPLAY 0.872340 (-3448 2250);
PAINT GREEN (-3448 2250);
DISPLAY INVISIBLE (-3448 2250);
FORCEADD TAP..6
R 2
(-3450 2150);
FORCEPROP 3 LASTPIN (-3500 2150) SIG_NAME P5E_CPU1_P3_TX_DP<10>
J 0
(-3490 2160);
DISPLAY 0.659574 (-3490 2160);
PAINT MONO (-3490 2160);
DISPLAY INVISIBLE (-3490 2160);
FORCEPROP 1 LASTPIN (-3500 2150) BN 10
J 2
(-3448 2158);
DISPLAY 0.489362 (-3448 2158);
PAINT MONO (-3448 2158);
FORCEPROP 2 LAST BOM_COST IO_SLOT
J 0
(-3950 2250);
DISPLAY 0.829787 (-3950 2250);
DISPLAY INVISIBLE (-3950 2250);
FORCEPROP 2 LAST CDS_LIB standard
J 0
(-3450 2150);
DISPLAY INVISIBLE (-3450 2150);
FORCEPROP 2 LAST ROOM RISER1
J 0
(-3950 2200);
DISPLAY 0.829787 (-3950 2200);
PAINT RED (-3950 2200);
DISPLAY INVISIBLE (-3950 2200);
FORCEPROP 1 LAST BODY_TYPE PLUMBING
J 2
(-3450 2100);
DISPLAY 0.702128 (-3450 2100);
PAINT GREEN (-3450 2100);
DISPLAY INVISIBLE (-3450 2100);
FORCEPROP 1 LAST HDL_TAP TRUE
J 2
(-3775 2025);
DISPLAY 0.702128 (-3775 2025);
PAINT GREEN (-3775 2025);
DISPLAY INVISIBLE (-3775 2025);
FORCEPROP 1 LAST PATH I206
J 2
(-3448 2150);
DISPLAY 0.872340 (-3448 2150);
PAINT GREEN (-3448 2150);
DISPLAY INVISIBLE (-3448 2150);
FORCEADD TAP..6
R 2
(-3450 2050);
FORCEPROP 3 LASTPIN (-3500 2050) SIG_NAME P5E_CPU1_P3_TX_DP<11>
J 0
(-3490 2060);
DISPLAY 0.659574 (-3490 2060);
PAINT MONO (-3490 2060);
DISPLAY INVISIBLE (-3490 2060);
FORCEPROP 1 LASTPIN (-3500 2050) BN 11
J 2
(-3448 2058);
DISPLAY 0.489362 (-3448 2058);
PAINT MONO (-3448 2058);
FORCEPROP 2 LAST BOM_COST IO_SLOT
J 0
(-3950 2150);
DISPLAY 0.829787 (-3950 2150);
DISPLAY INVISIBLE (-3950 2150);
FORCEPROP 2 LAST CDS_LIB standard
J 0
(-3450 2050);
DISPLAY INVISIBLE (-3450 2050);
FORCEPROP 2 LAST ROOM RISER1
J 0
(-3950 2100);
DISPLAY 0.829787 (-3950 2100);
PAINT RED (-3950 2100);
DISPLAY INVISIBLE (-3950 2100);
FORCEPROP 1 LAST BODY_TYPE PLUMBING
J 2
(-3450 2000);
DISPLAY 0.702128 (-3450 2000);
PAINT GREEN (-3450 2000);
DISPLAY INVISIBLE (-3450 2000);
FORCEPROP 1 LAST HDL_TAP TRUE
J 2
(-3775 1925);
DISPLAY 0.702128 (-3775 1925);
PAINT GREEN (-3775 1925);
DISPLAY INVISIBLE (-3775 1925);
FORCEPROP 1 LAST PATH I207
J 2
(-3448 2050);
DISPLAY 0.872340 (-3448 2050);
PAINT GREEN (-3448 2050);
DISPLAY INVISIBLE (-3448 2050);
FORCEADD TAP..6
R 2
(-3300 1800);
FORCEPROP 3 LASTPIN (-3350 1800) SIG_NAME P5E_CPU1_P3_TX_DN<13>
J 0
(-3340 1810);
DISPLAY 0.659574 (-3340 1810);
PAINT MONO (-3340 1810);
DISPLAY INVISIBLE (-3340 1810);
FORCEPROP 1 LASTPIN (-3350 1800) BN 13
J 2
(-3298 1808);
DISPLAY 0.489362 (-3298 1808);
PAINT MONO (-3298 1808);
FORCEPROP 2 LAST BOM_COST IO_SLOT
J 0
(-3800 1900);
DISPLAY 0.829787 (-3800 1900);
DISPLAY INVISIBLE (-3800 1900);
FORCEPROP 2 LAST CDS_LIB standard
J 0
(-3300 1800);
DISPLAY INVISIBLE (-3300 1800);
FORCEPROP 2 LAST ROOM RISER1
J 0
(-3800 1850);
DISPLAY 0.829787 (-3800 1850);
PAINT RED (-3800 1850);
DISPLAY INVISIBLE (-3800 1850);
FORCEPROP 1 LAST BODY_TYPE PLUMBING
J 2
(-3300 1750);
DISPLAY 0.702128 (-3300 1750);
PAINT GREEN (-3300 1750);
DISPLAY INVISIBLE (-3300 1750);
FORCEPROP 1 LAST HDL_TAP TRUE
J 2
(-3625 1675);
DISPLAY 0.702128 (-3625 1675);
PAINT GREEN (-3625 1675);
DISPLAY INVISIBLE (-3625 1675);
FORCEPROP 1 LAST PATH I208
J 2
(-3298 1800);
DISPLAY 0.872340 (-3298 1800);
PAINT GREEN (-3298 1800);
DISPLAY INVISIBLE (-3298 1800);
FORCEADD TAP..6
R 2
(-3300 1900);
FORCEPROP 3 LASTPIN (-3350 1900) SIG_NAME P5E_CPU1_P3_TX_DN<12>
J 0
(-3340 1910);
DISPLAY 0.659574 (-3340 1910);
PAINT MONO (-3340 1910);
DISPLAY INVISIBLE (-3340 1910);
FORCEPROP 1 LASTPIN (-3350 1900) BN 12
J 2
(-3298 1908);
DISPLAY 0.489362 (-3298 1908);
PAINT MONO (-3298 1908);
FORCEPROP 2 LAST BOM_COST IO_SLOT
J 0
(-3800 2000);
DISPLAY 0.829787 (-3800 2000);
DISPLAY INVISIBLE (-3800 2000);
FORCEPROP 2 LAST CDS_LIB standard
J 0
(-3300 1900);
DISPLAY INVISIBLE (-3300 1900);
FORCEPROP 2 LAST ROOM RISER1
J 0
(-3800 1950);
DISPLAY 0.829787 (-3800 1950);
PAINT RED (-3800 1950);
DISPLAY INVISIBLE (-3800 1950);
FORCEPROP 1 LAST BODY_TYPE PLUMBING
J 2
(-3300 1850);
DISPLAY 0.702128 (-3300 1850);
PAINT GREEN (-3300 1850);
DISPLAY INVISIBLE (-3300 1850);
FORCEPROP 1 LAST HDL_TAP TRUE
J 2
(-3625 1775);
DISPLAY 0.702128 (-3625 1775);
PAINT GREEN (-3625 1775);
DISPLAY INVISIBLE (-3625 1775);
FORCEPROP 1 LAST PATH I209
J 2
(-3298 1900);
DISPLAY 0.872340 (-3298 1900);
PAINT GREEN (-3298 1900);
DISPLAY INVISIBLE (-3298 1900);
FORCEADD TAP..6
R 2
(-3300 2000);
FORCEPROP 3 LASTPIN (-3350 2000) SIG_NAME P5E_CPU1_P3_TX_DN<11>
J 0
(-3340 2010);
DISPLAY 0.659574 (-3340 2010);
PAINT MONO (-3340 2010);
DISPLAY INVISIBLE (-3340 2010);
FORCEPROP 1 LASTPIN (-3350 2000) BN 11
J 2
(-3298 2008);
DISPLAY 0.489362 (-3298 2008);
PAINT MONO (-3298 2008);
FORCEPROP 2 LAST BOM_COST IO_SLOT
J 0
(-3800 2100);
DISPLAY 0.829787 (-3800 2100);
DISPLAY INVISIBLE (-3800 2100);
FORCEPROP 2 LAST CDS_LIB standard
J 0
(-3300 2000);
DISPLAY INVISIBLE (-3300 2000);
FORCEPROP 2 LAST ROOM RISER1
J 0
(-3800 2050);
DISPLAY 0.829787 (-3800 2050);
PAINT RED (-3800 2050);
DISPLAY INVISIBLE (-3800 2050);
FORCEPROP 1 LAST BODY_TYPE PLUMBING
J 2
(-3300 1950);
DISPLAY 0.702128 (-3300 1950);
PAINT GREEN (-3300 1950);
DISPLAY INVISIBLE (-3300 1950);
FORCEPROP 1 LAST HDL_TAP TRUE
J 2
(-3625 1875);
DISPLAY 0.702128 (-3625 1875);
PAINT GREEN (-3625 1875);
DISPLAY INVISIBLE (-3625 1875);
FORCEPROP 1 LAST PATH I210
J 2
(-3298 2000);
DISPLAY 0.872340 (-3298 2000);
PAINT GREEN (-3298 2000);
DISPLAY INVISIBLE (-3298 2000);
FORCEADD TAP..6
R 2
(-3450 1950);
FORCEPROP 3 LASTPIN (-3500 1950) SIG_NAME P5E_CPU1_P3_TX_DP<12>
J 0
(-3490 1960);
DISPLAY 0.659574 (-3490 1960);
PAINT MONO (-3490 1960);
DISPLAY INVISIBLE (-3490 1960);
FORCEPROP 1 LASTPIN (-3500 1950) BN 12
J 2
(-3448 1958);
DISPLAY 0.489362 (-3448 1958);
PAINT MONO (-3448 1958);
FORCEPROP 2 LAST BOM_COST IO_SLOT
J 0
(-3950 2050);
DISPLAY 0.829787 (-3950 2050);
DISPLAY INVISIBLE (-3950 2050);
FORCEPROP 2 LAST CDS_LIB standard
J 0
(-3450 1950);
DISPLAY INVISIBLE (-3450 1950);
FORCEPROP 2 LAST ROOM RISER1
J 0
(-3950 2000);
DISPLAY 0.829787 (-3950 2000);
PAINT RED (-3950 2000);
DISPLAY INVISIBLE (-3950 2000);
FORCEPROP 1 LAST BODY_TYPE PLUMBING
J 2
(-3450 1900);
DISPLAY 0.702128 (-3450 1900);
PAINT GREEN (-3450 1900);
DISPLAY INVISIBLE (-3450 1900);
FORCEPROP 1 LAST HDL_TAP TRUE
J 2
(-3775 1825);
DISPLAY 0.702128 (-3775 1825);
PAINT GREEN (-3775 1825);
DISPLAY INVISIBLE (-3775 1825);
FORCEPROP 1 LAST PATH I211
J 2
(-3448 1950);
DISPLAY 0.872340 (-3448 1950);
PAINT GREEN (-3448 1950);
DISPLAY INVISIBLE (-3448 1950);
FORCEADD TAP..6
R 2
(-3450 1850);
FORCEPROP 3 LASTPIN (-3500 1850) SIG_NAME P5E_CPU1_P3_TX_DP<13>
J 0
(-3490 1860);
DISPLAY 0.659574 (-3490 1860);
PAINT MONO (-3490 1860);
DISPLAY INVISIBLE (-3490 1860);
FORCEPROP 1 LASTPIN (-3500 1850) BN 13
J 2
(-3448 1858);
DISPLAY 0.489362 (-3448 1858);
PAINT MONO (-3448 1858);
FORCEPROP 2 LAST BOM_COST IO_SLOT
J 0
(-3950 1950);
DISPLAY 0.829787 (-3950 1950);
DISPLAY INVISIBLE (-3950 1950);
FORCEPROP 2 LAST CDS_LIB standard
J 0
(-3450 1850);
DISPLAY INVISIBLE (-3450 1850);
FORCEPROP 2 LAST ROOM RISER1
J 0
(-3950 1900);
DISPLAY 0.829787 (-3950 1900);
PAINT RED (-3950 1900);
DISPLAY INVISIBLE (-3950 1900);
FORCEPROP 1 LAST BODY_TYPE PLUMBING
J 2
(-3450 1800);
DISPLAY 0.702128 (-3450 1800);
PAINT GREEN (-3450 1800);
DISPLAY INVISIBLE (-3450 1800);
FORCEPROP 1 LAST HDL_TAP TRUE
J 2
(-3775 1725);
DISPLAY 0.702128 (-3775 1725);
PAINT GREEN (-3775 1725);
DISPLAY INVISIBLE (-3775 1725);
FORCEPROP 1 LAST PATH I212
J 2
(-3448 1850);
DISPLAY 0.872340 (-3448 1850);
PAINT GREEN (-3448 1850);
DISPLAY INVISIBLE (-3448 1850);
FORCEADD TAP..6
R 2
(-3300 1600);
FORCEPROP 3 LASTPIN (-3350 1600) SIG_NAME P5E_CPU1_P3_TX_DN<15>
J 0
(-3340 1610);
DISPLAY 0.659574 (-3340 1610);
PAINT MONO (-3340 1610);
DISPLAY INVISIBLE (-3340 1610);
FORCEPROP 1 LASTPIN (-3350 1600) BN 15
J 2
(-3298 1608);
DISPLAY 0.489362 (-3298 1608);
PAINT MONO (-3298 1608);
FORCEPROP 2 LAST BOM_COST IO_SLOT
J 0
(-3800 1700);
DISPLAY 0.829787 (-3800 1700);
DISPLAY INVISIBLE (-3800 1700);
FORCEPROP 2 LAST CDS_LIB standard
J 0
(-3300 1600);
DISPLAY INVISIBLE (-3300 1600);
FORCEPROP 2 LAST ROOM RISER1
J 0
(-3800 1650);
DISPLAY 0.829787 (-3800 1650);
PAINT RED (-3800 1650);
DISPLAY INVISIBLE (-3800 1650);
FORCEPROP 1 LAST BODY_TYPE PLUMBING
J 2
(-3300 1550);
DISPLAY 0.702128 (-3300 1550);
PAINT GREEN (-3300 1550);
DISPLAY INVISIBLE (-3300 1550);
FORCEPROP 1 LAST HDL_TAP TRUE
J 2
(-3625 1475);
DISPLAY 0.702128 (-3625 1475);
PAINT GREEN (-3625 1475);
DISPLAY INVISIBLE (-3625 1475);
FORCEPROP 1 LAST PATH I213
J 2
(-3298 1600);
DISPLAY 0.872340 (-3298 1600);
PAINT GREEN (-3298 1600);
DISPLAY INVISIBLE (-3298 1600);
FORCEADD TAP..6
R 2
(-3300 1700);
FORCEPROP 3 LASTPIN (-3350 1700) SIG_NAME P5E_CPU1_P3_TX_DN<14>
J 0
(-3340 1710);
DISPLAY 0.659574 (-3340 1710);
PAINT MONO (-3340 1710);
DISPLAY INVISIBLE (-3340 1710);
FORCEPROP 1 LASTPIN (-3350 1700) BN 14
J 2
(-3298 1708);
DISPLAY 0.489362 (-3298 1708);
PAINT MONO (-3298 1708);
FORCEPROP 2 LAST CDS_LIB standard
J 0
(-3300 1700);
DISPLAY INVISIBLE (-3300 1700);
FORCEPROP 2 LAST BOM_COST IO_SLOT
J 0
(-3800 1800);
DISPLAY 0.829787 (-3800 1800);
DISPLAY INVISIBLE (-3800 1800);
FORCEPROP 2 LAST ROOM RISER1
J 0
(-3800 1750);
DISPLAY 0.829787 (-3800 1750);
PAINT RED (-3800 1750);
DISPLAY INVISIBLE (-3800 1750);
FORCEPROP 1 LAST BODY_TYPE PLUMBING
J 2
(-3300 1650);
DISPLAY 0.702128 (-3300 1650);
PAINT GREEN (-3300 1650);
DISPLAY INVISIBLE (-3300 1650);
FORCEPROP 1 LAST HDL_TAP TRUE
J 2
(-3625 1575);
DISPLAY 0.702128 (-3625 1575);
PAINT GREEN (-3625 1575);
DISPLAY INVISIBLE (-3625 1575);
FORCEPROP 1 LAST PATH I214
J 2
(-3298 1700);
DISPLAY 0.872340 (-3298 1700);
PAINT GREEN (-3298 1700);
DISPLAY INVISIBLE (-3298 1700);
FORCEADD TAP..6
R 2
(-3450 1750);
FORCEPROP 3 LASTPIN (-3500 1750) SIG_NAME P5E_CPU1_P3_TX_DP<14>
J 0
(-3490 1760);
DISPLAY 0.659574 (-3490 1760);
PAINT MONO (-3490 1760);
DISPLAY INVISIBLE (-3490 1760);
FORCEPROP 1 LASTPIN (-3500 1750) BN 14
J 2
(-3448 1758);
DISPLAY 0.489362 (-3448 1758);
PAINT MONO (-3448 1758);
FORCEPROP 2 LAST BOM_COST IO_SLOT
J 0
(-3950 1850);
DISPLAY 0.829787 (-3950 1850);
DISPLAY INVISIBLE (-3950 1850);
FORCEPROP 2 LAST CDS_LIB standard
J 0
(-3450 1750);
DISPLAY INVISIBLE (-3450 1750);
FORCEPROP 2 LAST ROOM RISER1
J 0
(-3950 1800);
DISPLAY 0.829787 (-3950 1800);
PAINT RED (-3950 1800);
DISPLAY INVISIBLE (-3950 1800);
FORCEPROP 1 LAST BODY_TYPE PLUMBING
J 2
(-3450 1700);
DISPLAY 0.702128 (-3450 1700);
PAINT GREEN (-3450 1700);
DISPLAY INVISIBLE (-3450 1700);
FORCEPROP 1 LAST HDL_TAP TRUE
J 2
(-3775 1625);
DISPLAY 0.702128 (-3775 1625);
PAINT GREEN (-3775 1625);
DISPLAY INVISIBLE (-3775 1625);
FORCEPROP 1 LAST PATH I215
J 2
(-3448 1750);
DISPLAY 0.872340 (-3448 1750);
PAINT GREEN (-3448 1750);
DISPLAY INVISIBLE (-3448 1750);
FORCEADD TAP..6
R 2
(-3450 1650);
FORCEPROP 3 LASTPIN (-3500 1650) SIG_NAME P5E_CPU1_P3_TX_DP<15>
J 0
(-3490 1660);
DISPLAY 0.659574 (-3490 1660);
PAINT MONO (-3490 1660);
DISPLAY INVISIBLE (-3490 1660);
FORCEPROP 1 LASTPIN (-3500 1650) BN 15
J 2
(-3448 1658);
DISPLAY 0.489362 (-3448 1658);
PAINT MONO (-3448 1658);
FORCEPROP 2 LAST BOM_COST IO_SLOT
J 0
(-3950 1750);
DISPLAY 0.829787 (-3950 1750);
DISPLAY INVISIBLE (-3950 1750);
FORCEPROP 2 LAST CDS_LIB standard
J 0
(-3450 1650);
DISPLAY INVISIBLE (-3450 1650);
FORCEPROP 2 LAST ROOM RISER1
J 0
(-3950 1700);
DISPLAY 0.829787 (-3950 1700);
PAINT RED (-3950 1700);
DISPLAY INVISIBLE (-3950 1700);
FORCEPROP 1 LAST BODY_TYPE PLUMBING
J 2
(-3450 1600);
DISPLAY 0.702128 (-3450 1600);
PAINT GREEN (-3450 1600);
DISPLAY INVISIBLE (-3450 1600);
FORCEPROP 1 LAST HDL_TAP TRUE
J 2
(-3775 1525);
DISPLAY 0.702128 (-3775 1525);
PAINT GREEN (-3775 1525);
DISPLAY INVISIBLE (-3775 1525);
FORCEPROP 1 LAST PATH I216
J 2
(-3448 1650);
DISPLAY 0.872340 (-3448 1650);
PAINT GREEN (-3448 1650);
DISPLAY INVISIBLE (-3448 1650);
FORCEADD TAP..6
(-5875 3150);
FORCEPROP 3 LASTPIN (-5825 3150) SIG_NAME P5E_CPU1_P3_RX_DP<0>
J 0
(-5815 3160);
DISPLAY 0.659574 (-5815 3160);
PAINT MONO (-5815 3160);
DISPLAY INVISIBLE (-5815 3160);
FORCEPROP 1 LASTPIN (-5825 3150) BN 0
J 0
(-5877 3158);
DISPLAY 0.489362 (-5877 3158);
PAINT MONO (-5877 3158);
FORCEPROP 2 LAST CDS_LIB mstr_standard
J 0
(-5875 3150);
DISPLAY INVISIBLE (-5875 3150);
FORCEPROP 1 LAST BODY_TYPE PLUMBING
J 0
(-5875 3100);
DISPLAY 0.574468 (-5875 3100);
PAINT GREEN (-5875 3100);
DISPLAY INVISIBLE (-5875 3100);
FORCEPROP 1 LAST HDL_TAP TRUE
J 0
(-5550 3025);
DISPLAY 0.574468 (-5550 3025);
PAINT GREEN (-5550 3025);
DISPLAY INVISIBLE (-5550 3025);
FORCEPROP 1 LAST PATH I251
J 0
(-5877 3150);
DISPLAY 0.872340 (-5877 3150);
PAINT GREEN (-5877 3150);
DISPLAY INVISIBLE (-5877 3150);
FORCEADD TAP..6
(-5875 2950);
FORCEPROP 3 LASTPIN (-5825 2950) SIG_NAME P5E_CPU1_P3_RX_DP<2>
J 0
(-5815 2960);
DISPLAY 0.659574 (-5815 2960);
PAINT MONO (-5815 2960);
DISPLAY INVISIBLE (-5815 2960);
FORCEPROP 1 LASTPIN (-5825 2950) BN 2
J 0
(-5877 2958);
DISPLAY 0.489362 (-5877 2958);
PAINT MONO (-5877 2958);
FORCEPROP 2 LAST CDS_LIB mstr_standard
J 0
(-5875 2950);
DISPLAY INVISIBLE (-5875 2950);
FORCEPROP 1 LAST BODY_TYPE PLUMBING
J 0
(-5875 2900);
DISPLAY 0.574468 (-5875 2900);
PAINT GREEN (-5875 2900);
DISPLAY INVISIBLE (-5875 2900);
FORCEPROP 1 LAST HDL_TAP TRUE
J 0
(-5550 2825);
DISPLAY 0.574468 (-5550 2825);
PAINT GREEN (-5550 2825);
DISPLAY INVISIBLE (-5550 2825);
FORCEPROP 1 LAST PATH I253
J 0
(-5877 2950);
DISPLAY 0.872340 (-5877 2950);
PAINT GREEN (-5877 2950);
DISPLAY INVISIBLE (-5877 2950);
FORCEADD TAP..6
(-5875 3050);
FORCEPROP 3 LASTPIN (-5825 3050) SIG_NAME P5E_CPU1_P3_RX_DP<1>
J 0
(-5815 3060);
DISPLAY 0.659574 (-5815 3060);
PAINT MONO (-5815 3060);
DISPLAY INVISIBLE (-5815 3060);
FORCEPROP 1 LASTPIN (-5825 3050) BN 1
J 0
(-5877 3058);
DISPLAY 0.489362 (-5877 3058);
PAINT MONO (-5877 3058);
FORCEPROP 2 LAST CDS_LIB mstr_standard
J 0
(-5875 3050);
DISPLAY INVISIBLE (-5875 3050);
FORCEPROP 1 LAST BODY_TYPE PLUMBING
J 0
(-5875 3000);
DISPLAY 0.574468 (-5875 3000);
PAINT GREEN (-5875 3000);
DISPLAY INVISIBLE (-5875 3000);
FORCEPROP 1 LAST HDL_TAP TRUE
J 0
(-5550 2925);
DISPLAY 0.574468 (-5550 2925);
PAINT GREEN (-5550 2925);
DISPLAY INVISIBLE (-5550 2925);
FORCEPROP 1 LAST PATH I254
J 0
(-5877 3050);
DISPLAY 0.872340 (-5877 3050);
PAINT GREEN (-5877 3050);
DISPLAY INVISIBLE (-5877 3050);
FORCEADD TAP..6
(-5875 2850);
FORCEPROP 3 LASTPIN (-5825 2850) SIG_NAME P5E_CPU1_P3_RX_DP<3>
J 0
(-5815 2860);
DISPLAY 0.659574 (-5815 2860);
PAINT MONO (-5815 2860);
DISPLAY INVISIBLE (-5815 2860);
FORCEPROP 1 LASTPIN (-5825 2850) BN 3
J 0
(-5877 2858);
DISPLAY 0.489362 (-5877 2858);
PAINT MONO (-5877 2858);
FORCEPROP 2 LAST CDS_LIB standard
J 0
(-5875 2850);
DISPLAY INVISIBLE (-5875 2850);
FORCEPROP 1 LAST BODY_TYPE PLUMBING
J 0
(-5875 2800);
DISPLAY 0.574468 (-5875 2800);
PAINT GREEN (-5875 2800);
DISPLAY INVISIBLE (-5875 2800);
FORCEPROP 1 LAST HDL_TAP TRUE
J 0
(-5550 2725);
DISPLAY 0.574468 (-5550 2725);
PAINT GREEN (-5550 2725);
DISPLAY INVISIBLE (-5550 2725);
FORCEPROP 1 LAST PATH I255
J 0
(-5877 2850);
DISPLAY 0.872340 (-5877 2850);
PAINT GREEN (-5877 2850);
DISPLAY INVISIBLE (-5877 2850);
FORCEADD TAP..6
(-5875 2750);
FORCEPROP 3 LASTPIN (-5825 2750) SIG_NAME P5E_CPU1_P3_RX_DP<4>
J 0
(-5815 2760);
DISPLAY 0.659574 (-5815 2760);
PAINT MONO (-5815 2760);
DISPLAY INVISIBLE (-5815 2760);
FORCEPROP 1 LASTPIN (-5825 2750) BN 4
J 0
(-5877 2758);
DISPLAY 0.489362 (-5877 2758);
PAINT MONO (-5877 2758);
FORCEPROP 2 LAST CDS_LIB standard
J 0
(-5875 2750);
DISPLAY INVISIBLE (-5875 2750);
FORCEPROP 1 LAST BODY_TYPE PLUMBING
J 0
(-5875 2700);
DISPLAY 0.574468 (-5875 2700);
PAINT GREEN (-5875 2700);
DISPLAY INVISIBLE (-5875 2700);
FORCEPROP 1 LAST HDL_TAP TRUE
J 0
(-5550 2625);
DISPLAY 0.574468 (-5550 2625);
PAINT GREEN (-5550 2625);
DISPLAY INVISIBLE (-5550 2625);
FORCEPROP 1 LAST PATH I256
J 0
(-5877 2750);
DISPLAY 0.872340 (-5877 2750);
PAINT GREEN (-5877 2750);
DISPLAY INVISIBLE (-5877 2750);
FORCEADD TAP..6
(-5875 2650);
FORCEPROP 3 LASTPIN (-5825 2650) SIG_NAME P5E_CPU1_P3_RX_DP<5>
J 0
(-5815 2660);
DISPLAY 0.659574 (-5815 2660);
PAINT MONO (-5815 2660);
DISPLAY INVISIBLE (-5815 2660);
FORCEPROP 1 LASTPIN (-5825 2650) BN 5
J 0
(-5877 2658);
DISPLAY 0.489362 (-5877 2658);
PAINT MONO (-5877 2658);
FORCEPROP 2 LAST CDS_LIB standard
J 0
(-5875 2650);
DISPLAY INVISIBLE (-5875 2650);
FORCEPROP 1 LAST BODY_TYPE PLUMBING
J 0
(-5875 2600);
DISPLAY 0.574468 (-5875 2600);
PAINT GREEN (-5875 2600);
DISPLAY INVISIBLE (-5875 2600);
FORCEPROP 1 LAST HDL_TAP TRUE
J 0
(-5550 2525);
DISPLAY 0.574468 (-5550 2525);
PAINT GREEN (-5550 2525);
DISPLAY INVISIBLE (-5550 2525);
FORCEPROP 1 LAST PATH I257
J 0
(-5877 2650);
DISPLAY 0.872340 (-5877 2650);
PAINT GREEN (-5877 2650);
DISPLAY INVISIBLE (-5877 2650);
FORCEADD TAP..6
(-5875 2550);
FORCEPROP 3 LASTPIN (-5825 2550) SIG_NAME P5E_CPU1_P3_RX_DP<6>
J 0
(-5815 2560);
DISPLAY 0.659574 (-5815 2560);
PAINT MONO (-5815 2560);
DISPLAY INVISIBLE (-5815 2560);
FORCEPROP 1 LASTPIN (-5825 2550) BN 6
J 0
(-5877 2558);
DISPLAY 0.489362 (-5877 2558);
PAINT MONO (-5877 2558);
FORCEPROP 2 LAST CDS_LIB standard
J 0
(-5875 2550);
DISPLAY INVISIBLE (-5875 2550);
FORCEPROP 1 LAST BODY_TYPE PLUMBING
J 0
(-5875 2500);
DISPLAY 0.574468 (-5875 2500);
PAINT GREEN (-5875 2500);
DISPLAY INVISIBLE (-5875 2500);
FORCEPROP 1 LAST HDL_TAP TRUE
J 0
(-5550 2425);
DISPLAY 0.574468 (-5550 2425);
PAINT GREEN (-5550 2425);
DISPLAY INVISIBLE (-5550 2425);
FORCEPROP 1 LAST PATH I263
J 0
(-5877 2550);
DISPLAY 0.872340 (-5877 2550);
PAINT GREEN (-5877 2550);
DISPLAY INVISIBLE (-5877 2550);
FORCEADD TAP..6
(-5875 2450);
FORCEPROP 3 LASTPIN (-5825 2450) SIG_NAME P5E_CPU1_P3_RX_DP<7>
J 0
(-5815 2460);
DISPLAY 0.659574 (-5815 2460);
PAINT MONO (-5815 2460);
DISPLAY INVISIBLE (-5815 2460);
FORCEPROP 1 LASTPIN (-5825 2450) BN 7
J 0
(-5877 2458);
DISPLAY 0.489362 (-5877 2458);
PAINT MONO (-5877 2458);
FORCEPROP 2 LAST CDS_LIB mstr_standard
J 0
(-5875 2450);
DISPLAY INVISIBLE (-5875 2450);
FORCEPROP 1 LAST BODY_TYPE PLUMBING
J 0
(-5875 2400);
DISPLAY 0.574468 (-5875 2400);
PAINT GREEN (-5875 2400);
DISPLAY INVISIBLE (-5875 2400);
FORCEPROP 1 LAST HDL_TAP TRUE
J 0
(-5550 2325);
DISPLAY 0.574468 (-5550 2325);
PAINT GREEN (-5550 2325);
DISPLAY INVISIBLE (-5550 2325);
FORCEPROP 1 LAST PATH I285
J 0
(-5877 2450);
DISPLAY 0.872340 (-5877 2450);
PAINT GREEN (-5877 2450);
DISPLAY INVISIBLE (-5877 2450);
FORCEADD TAP..6
(-5875 2050);
FORCEPROP 3 LASTPIN (-5825 2050) SIG_NAME P5E_CPU1_P3_RX_DP<11>
J 0
(-5815 2060);
DISPLAY 0.659574 (-5815 2060);
PAINT MONO (-5815 2060);
DISPLAY INVISIBLE (-5815 2060);
FORCEPROP 1 LASTPIN (-5825 2050) BN 11
J 0
(-5877 2058);
DISPLAY 0.489362 (-5877 2058);
PAINT MONO (-5877 2058);
FORCEPROP 2 LAST CDS_LIB standard
J 0
(-5875 2050);
DISPLAY INVISIBLE (-5875 2050);
FORCEPROP 1 LAST BODY_TYPE PLUMBING
J 0
(-5875 2000);
DISPLAY 0.574468 (-5875 2000);
PAINT GREEN (-5875 2000);
DISPLAY INVISIBLE (-5875 2000);
FORCEPROP 1 LAST HDL_TAP TRUE
J 0
(-5550 1925);
DISPLAY 0.574468 (-5550 1925);
PAINT GREEN (-5550 1925);
DISPLAY INVISIBLE (-5550 1925);
FORCEPROP 1 LAST PATH I286
J 0
(-5877 2050);
DISPLAY 0.872340 (-5877 2050);
PAINT GREEN (-5877 2050);
DISPLAY INVISIBLE (-5877 2050);
FORCEADD TAP..6
(-5875 1950);
FORCEPROP 3 LASTPIN (-5825 1950) SIG_NAME P5E_CPU1_P3_RX_DP<12>
J 0
(-5815 1960);
DISPLAY 0.659574 (-5815 1960);
PAINT MONO (-5815 1960);
DISPLAY INVISIBLE (-5815 1960);
FORCEPROP 1 LASTPIN (-5825 1950) BN 12
J 0
(-5877 1958);
DISPLAY 0.489362 (-5877 1958);
PAINT MONO (-5877 1958);
FORCEPROP 2 LAST CDS_LIB standard
J 0
(-5875 1950);
DISPLAY INVISIBLE (-5875 1950);
FORCEPROP 1 LAST BODY_TYPE PLUMBING
J 0
(-5875 1900);
DISPLAY 0.574468 (-5875 1900);
PAINT GREEN (-5875 1900);
DISPLAY INVISIBLE (-5875 1900);
FORCEPROP 1 LAST HDL_TAP TRUE
J 0
(-5550 1825);
DISPLAY 0.574468 (-5550 1825);
PAINT GREEN (-5550 1825);
DISPLAY INVISIBLE (-5550 1825);
FORCEPROP 1 LAST PATH I287
J 0
(-5877 1950);
DISPLAY 0.872340 (-5877 1950);
PAINT GREEN (-5877 1950);
DISPLAY INVISIBLE (-5877 1950);
FORCEADD TAP..6
(-5875 1850);
FORCEPROP 3 LASTPIN (-5825 1850) SIG_NAME P5E_CPU1_P3_RX_DP<13>
J 0
(-5815 1860);
DISPLAY 0.659574 (-5815 1860);
PAINT MONO (-5815 1860);
DISPLAY INVISIBLE (-5815 1860);
FORCEPROP 1 LASTPIN (-5825 1850) BN 13
J 0
(-5877 1858);
DISPLAY 0.489362 (-5877 1858);
PAINT MONO (-5877 1858);
FORCEPROP 2 LAST CDS_LIB standard
J 0
(-5875 1850);
DISPLAY INVISIBLE (-5875 1850);
FORCEPROP 1 LAST BODY_TYPE PLUMBING
J 0
(-5875 1800);
DISPLAY 0.574468 (-5875 1800);
PAINT GREEN (-5875 1800);
DISPLAY INVISIBLE (-5875 1800);
FORCEPROP 1 LAST HDL_TAP TRUE
J 0
(-5550 1725);
DISPLAY 0.574468 (-5550 1725);
PAINT GREEN (-5550 1725);
DISPLAY INVISIBLE (-5550 1725);
FORCEPROP 1 LAST PATH I288
J 0
(-5877 1850);
DISPLAY 0.872340 (-5877 1850);
PAINT GREEN (-5877 1850);
DISPLAY INVISIBLE (-5877 1850);
FORCEADD TAP..6
(-5875 2350);
FORCEPROP 3 LASTPIN (-5825 2350) SIG_NAME P5E_CPU1_P3_RX_DP<8>
J 0
(-5815 2360);
DISPLAY 0.659574 (-5815 2360);
PAINT MONO (-5815 2360);
DISPLAY INVISIBLE (-5815 2360);
FORCEPROP 1 LASTPIN (-5825 2350) BN 8
J 0
(-5877 2358);
DISPLAY 0.489362 (-5877 2358);
PAINT MONO (-5877 2358);
FORCEPROP 2 LAST CDS_LIB mstr_standard
J 0
(-5875 2350);
DISPLAY INVISIBLE (-5875 2350);
FORCEPROP 1 LAST BODY_TYPE PLUMBING
J 0
(-5875 2300);
DISPLAY 0.574468 (-5875 2300);
PAINT GREEN (-5875 2300);
DISPLAY INVISIBLE (-5875 2300);
FORCEPROP 1 LAST HDL_TAP TRUE
J 0
(-5550 2225);
DISPLAY 0.574468 (-5550 2225);
PAINT GREEN (-5550 2225);
DISPLAY INVISIBLE (-5550 2225);
FORCEPROP 1 LAST PATH I292
J 0
(-5877 2350);
DISPLAY 0.872340 (-5877 2350);
PAINT GREEN (-5877 2350);
DISPLAY INVISIBLE (-5877 2350);
FORCEADD TAP..6
(-5875 2250);
FORCEPROP 3 LASTPIN (-5825 2250) SIG_NAME P5E_CPU1_P3_RX_DP<9>
J 0
(-5815 2260);
DISPLAY 0.659574 (-5815 2260);
PAINT MONO (-5815 2260);
DISPLAY INVISIBLE (-5815 2260);
FORCEPROP 1 LASTPIN (-5825 2250) BN 9
J 0
(-5877 2258);
DISPLAY 0.489362 (-5877 2258);
PAINT MONO (-5877 2258);
FORCEPROP 2 LAST CDS_LIB mstr_standard
J 0
(-5875 2250);
DISPLAY INVISIBLE (-5875 2250);
FORCEPROP 1 LAST BODY_TYPE PLUMBING
J 0
(-5875 2200);
DISPLAY 0.574468 (-5875 2200);
PAINT GREEN (-5875 2200);
DISPLAY INVISIBLE (-5875 2200);
FORCEPROP 1 LAST HDL_TAP TRUE
J 0
(-5550 2125);
DISPLAY 0.574468 (-5550 2125);
PAINT GREEN (-5550 2125);
DISPLAY INVISIBLE (-5550 2125);
FORCEPROP 1 LAST PATH I293
J 0
(-5877 2250);
DISPLAY 0.872340 (-5877 2250);
PAINT GREEN (-5877 2250);
DISPLAY INVISIBLE (-5877 2250);
FORCEADD TAP..6
(-5875 2150);
FORCEPROP 3 LASTPIN (-5825 2150) SIG_NAME P5E_CPU1_P3_RX_DP<10>
J 0
(-5815 2160);
DISPLAY 0.659574 (-5815 2160);
PAINT MONO (-5815 2160);
DISPLAY INVISIBLE (-5815 2160);
FORCEPROP 1 LASTPIN (-5825 2150) BN 10
J 0
(-5877 2158);
DISPLAY 0.489362 (-5877 2158);
PAINT MONO (-5877 2158);
FORCEPROP 2 LAST CDS_LIB standard
J 0
(-5875 2150);
DISPLAY INVISIBLE (-5875 2150);
FORCEPROP 1 LAST BODY_TYPE PLUMBING
J 0
(-5875 2100);
DISPLAY 0.574468 (-5875 2100);
PAINT GREEN (-5875 2100);
DISPLAY INVISIBLE (-5875 2100);
FORCEPROP 1 LAST HDL_TAP TRUE
J 0
(-5550 2025);
DISPLAY 0.574468 (-5550 2025);
PAINT GREEN (-5550 2025);
DISPLAY INVISIBLE (-5550 2025);
FORCEPROP 1 LAST PATH I294
J 0
(-5877 2150);
DISPLAY 0.872340 (-5877 2150);
PAINT GREEN (-5877 2150);
DISPLAY INVISIBLE (-5877 2150);
FORCEADD TAP..6
(-5875 1750);
FORCEPROP 3 LASTPIN (-5825 1750) SIG_NAME P5E_CPU1_P3_RX_DP<14>
J 0
(-5815 1760);
DISPLAY 0.659574 (-5815 1760);
PAINT MONO (-5815 1760);
DISPLAY INVISIBLE (-5815 1760);
FORCEPROP 1 LASTPIN (-5825 1750) BN 14
J 0
(-5877 1758);
DISPLAY 0.489362 (-5877 1758);
PAINT MONO (-5877 1758);
FORCEPROP 2 LAST CDS_LIB standard
J 0
(-5875 1750);
DISPLAY INVISIBLE (-5875 1750);
FORCEPROP 1 LAST BODY_TYPE PLUMBING
J 0
(-5875 1700);
DISPLAY 0.574468 (-5875 1700);
PAINT GREEN (-5875 1700);
DISPLAY INVISIBLE (-5875 1700);
FORCEPROP 1 LAST HDL_TAP TRUE
J 0
(-5550 1625);
DISPLAY 0.574468 (-5550 1625);
PAINT GREEN (-5550 1625);
DISPLAY INVISIBLE (-5550 1625);
FORCEPROP 1 LAST PATH I299
J 0
(-5877 1750);
DISPLAY 0.872340 (-5877 1750);
PAINT GREEN (-5877 1750);
DISPLAY INVISIBLE (-5877 1750);
FORCEADD TAP..6
(-5875 1650);
FORCEPROP 3 LASTPIN (-5825 1650) SIG_NAME P5E_CPU1_P3_RX_DP<15>
J 0
(-5815 1660);
DISPLAY 0.659574 (-5815 1660);
PAINT MONO (-5815 1660);
DISPLAY INVISIBLE (-5815 1660);
FORCEPROP 1 LASTPIN (-5825 1650) BN 15
J 0
(-5877 1658);
DISPLAY 0.489362 (-5877 1658);
PAINT MONO (-5877 1658);
FORCEPROP 2 LAST CDS_LIB standard
J 0
(-5875 1650);
DISPLAY INVISIBLE (-5875 1650);
FORCEPROP 1 LAST BODY_TYPE PLUMBING
J 0
(-5875 1600);
DISPLAY 0.574468 (-5875 1600);
PAINT GREEN (-5875 1600);
DISPLAY INVISIBLE (-5875 1600);
FORCEPROP 1 LAST HDL_TAP TRUE
J 0
(-5550 1525);
DISPLAY 0.574468 (-5550 1525);
PAINT GREEN (-5550 1525);
DISPLAY INVISIBLE (-5550 1525);
FORCEPROP 1 LAST PATH I302
J 0
(-5877 1650);
DISPLAY 0.872340 (-5877 1650);
PAINT GREEN (-5877 1650);
DISPLAY INVISIBLE (-5877 1650);
FORCEADD TAP..6
(-6025 3000);
FORCEPROP 3 LASTPIN (-5975 3000) SIG_NAME P5E_CPU1_P3_RX_DN<1>
J 0
(-5965 3010);
DISPLAY 0.659574 (-5965 3010);
PAINT MONO (-5965 3010);
DISPLAY INVISIBLE (-5965 3010);
FORCEPROP 1 LASTPIN (-5975 3000) BN 1
J 0
(-6027 3008);
DISPLAY 0.489362 (-6027 3008);
PAINT MONO (-6027 3008);
FORCEPROP 2 LAST CDS_LIB mstr_standard
J 0
(-6025 3000);
DISPLAY INVISIBLE (-6025 3000);
FORCEPROP 1 LAST BODY_TYPE PLUMBING
J 0
(-6025 2950);
DISPLAY 0.574468 (-6025 2950);
PAINT GREEN (-6025 2950);
DISPLAY INVISIBLE (-6025 2950);
FORCEPROP 1 LAST HDL_TAP TRUE
J 0
(-5700 2875);
DISPLAY 0.574468 (-5700 2875);
PAINT GREEN (-5700 2875);
DISPLAY INVISIBLE (-5700 2875);
FORCEPROP 1 LAST PATH I303
J 0
(-6027 3000);
DISPLAY 0.872340 (-6027 3000);
PAINT GREEN (-6027 3000);
DISPLAY INVISIBLE (-6027 3000);
FORCEADD TAP..6
(-6025 3100);
FORCEPROP 3 LASTPIN (-5975 3100) SIG_NAME P5E_CPU1_P3_RX_DN<0>
J 0
(-5965 3110);
DISPLAY 0.659574 (-5965 3110);
PAINT MONO (-5965 3110);
DISPLAY INVISIBLE (-5965 3110);
FORCEPROP 1 LASTPIN (-5975 3100) BN 0
J 0
(-6027 3108);
DISPLAY 0.489362 (-6027 3108);
PAINT MONO (-6027 3108);
FORCEPROP 2 LAST CDS_LIB mstr_standard
J 0
(-6025 3100);
DISPLAY INVISIBLE (-6025 3100);
FORCEPROP 1 LAST BODY_TYPE PLUMBING
J 0
(-6025 3050);
DISPLAY 0.574468 (-6025 3050);
PAINT GREEN (-6025 3050);
DISPLAY INVISIBLE (-6025 3050);
FORCEPROP 1 LAST HDL_TAP TRUE
J 0
(-5700 2975);
DISPLAY 0.574468 (-5700 2975);
PAINT GREEN (-5700 2975);
DISPLAY INVISIBLE (-5700 2975);
FORCEPROP 1 LAST PATH I304
J 0
(-6027 3100);
DISPLAY 0.872340 (-6027 3100);
PAINT GREEN (-6027 3100);
DISPLAY INVISIBLE (-6027 3100);
FORCEADD TAP..6
(-6025 2900);
FORCEPROP 3 LASTPIN (-5975 2900) SIG_NAME P5E_CPU1_P3_RX_DN<2>
J 0
(-5965 2910);
DISPLAY 0.659574 (-5965 2910);
PAINT MONO (-5965 2910);
DISPLAY INVISIBLE (-5965 2910);
FORCEPROP 1 LASTPIN (-5975 2900) BN 2
J 0
(-6027 2908);
DISPLAY 0.489362 (-6027 2908);
PAINT MONO (-6027 2908);
FORCEPROP 2 LAST CDS_LIB standard
J 0
(-6025 2900);
DISPLAY INVISIBLE (-6025 2900);
FORCEPROP 1 LAST BODY_TYPE PLUMBING
J 0
(-6025 2850);
DISPLAY 0.574468 (-6025 2850);
PAINT GREEN (-6025 2850);
DISPLAY INVISIBLE (-6025 2850);
FORCEPROP 1 LAST HDL_TAP TRUE
J 0
(-5700 2775);
DISPLAY 0.574468 (-5700 2775);
PAINT GREEN (-5700 2775);
DISPLAY INVISIBLE (-5700 2775);
FORCEPROP 1 LAST PATH I305
J 0
(-6027 2900);
DISPLAY 0.872340 (-6027 2900);
PAINT GREEN (-6027 2900);
DISPLAY INVISIBLE (-6027 2900);
FORCEADD TAP..6
(-6025 2800);
FORCEPROP 3 LASTPIN (-5975 2800) SIG_NAME P5E_CPU1_P3_RX_DN<3>
J 0
(-5965 2810);
DISPLAY 0.659574 (-5965 2810);
PAINT MONO (-5965 2810);
DISPLAY INVISIBLE (-5965 2810);
FORCEPROP 1 LASTPIN (-5975 2800) BN 3
J 0
(-6027 2808);
DISPLAY 0.489362 (-6027 2808);
PAINT MONO (-6027 2808);
FORCEPROP 2 LAST CDS_LIB standard
J 0
(-6025 2800);
DISPLAY INVISIBLE (-6025 2800);
FORCEPROP 1 LAST BODY_TYPE PLUMBING
J 0
(-6025 2750);
DISPLAY 0.574468 (-6025 2750);
PAINT GREEN (-6025 2750);
DISPLAY INVISIBLE (-6025 2750);
FORCEPROP 1 LAST HDL_TAP TRUE
J 0
(-5700 2675);
DISPLAY 0.574468 (-5700 2675);
PAINT GREEN (-5700 2675);
DISPLAY INVISIBLE (-5700 2675);
FORCEPROP 1 LAST PATH I306
J 0
(-6027 2800);
DISPLAY 0.872340 (-6027 2800);
PAINT GREEN (-6027 2800);
DISPLAY INVISIBLE (-6027 2800);
FORCEADD TAP..6
(-6025 2700);
FORCEPROP 3 LASTPIN (-5975 2700) SIG_NAME P5E_CPU1_P3_RX_DN<4>
J 0
(-5965 2710);
DISPLAY 0.659574 (-5965 2710);
PAINT MONO (-5965 2710);
DISPLAY INVISIBLE (-5965 2710);
FORCEPROP 1 LASTPIN (-5975 2700) BN 4
J 0
(-6027 2708);
DISPLAY 0.489362 (-6027 2708);
PAINT MONO (-6027 2708);
FORCEPROP 2 LAST CDS_LIB standard
J 0
(-6025 2700);
DISPLAY INVISIBLE (-6025 2700);
FORCEPROP 1 LAST BODY_TYPE PLUMBING
J 0
(-6025 2650);
DISPLAY 0.574468 (-6025 2650);
PAINT GREEN (-6025 2650);
DISPLAY INVISIBLE (-6025 2650);
FORCEPROP 1 LAST HDL_TAP TRUE
J 0
(-5700 2575);
DISPLAY 0.574468 (-5700 2575);
PAINT GREEN (-5700 2575);
DISPLAY INVISIBLE (-5700 2575);
FORCEPROP 1 LAST PATH I307
J 0
(-6027 2700);
DISPLAY 0.872340 (-6027 2700);
PAINT GREEN (-6027 2700);
DISPLAY INVISIBLE (-6027 2700);
FORCEADD TAP..6
(-6025 2600);
FORCEPROP 3 LASTPIN (-5975 2600) SIG_NAME P5E_CPU1_P3_RX_DN<5>
J 0
(-5965 2610);
DISPLAY 0.659574 (-5965 2610);
PAINT MONO (-5965 2610);
DISPLAY INVISIBLE (-5965 2610);
FORCEPROP 1 LASTPIN (-5975 2600) BN 5
J 0
(-6027 2608);
DISPLAY 0.489362 (-6027 2608);
PAINT MONO (-6027 2608);
FORCEPROP 2 LAST CDS_LIB standard
J 0
(-6025 2600);
DISPLAY INVISIBLE (-6025 2600);
FORCEPROP 1 LAST BODY_TYPE PLUMBING
J 0
(-6025 2550);
DISPLAY 0.574468 (-6025 2550);
PAINT GREEN (-6025 2550);
DISPLAY INVISIBLE (-6025 2550);
FORCEPROP 1 LAST HDL_TAP TRUE
J 0
(-5700 2475);
DISPLAY 0.574468 (-5700 2475);
PAINT GREEN (-5700 2475);
DISPLAY INVISIBLE (-5700 2475);
FORCEPROP 1 LAST PATH I308
J 0
(-6027 2600);
DISPLAY 0.872340 (-6027 2600);
PAINT GREEN (-6027 2600);
DISPLAY INVISIBLE (-6027 2600);
FORCEADD TAP..6
(-6025 2500);
FORCEPROP 3 LASTPIN (-5975 2500) SIG_NAME P5E_CPU1_P3_RX_DN<6>
J 0
(-5965 2510);
DISPLAY 0.659574 (-5965 2510);
PAINT MONO (-5965 2510);
DISPLAY INVISIBLE (-5965 2510);
FORCEPROP 1 LASTPIN (-5975 2500) BN 6
J 0
(-6027 2508);
DISPLAY 0.489362 (-6027 2508);
PAINT MONO (-6027 2508);
FORCEPROP 2 LAST CDS_LIB standard
J 0
(-6025 2500);
DISPLAY INVISIBLE (-6025 2500);
FORCEPROP 1 LAST BODY_TYPE PLUMBING
J 0
(-6025 2450);
DISPLAY 0.574468 (-6025 2450);
PAINT GREEN (-6025 2450);
DISPLAY INVISIBLE (-6025 2450);
FORCEPROP 1 LAST HDL_TAP TRUE
J 0
(-5700 2375);
DISPLAY 0.574468 (-5700 2375);
PAINT GREEN (-5700 2375);
DISPLAY INVISIBLE (-5700 2375);
FORCEPROP 1 LAST PATH I309
J 0
(-6027 2500);
DISPLAY 0.872340 (-6027 2500);
PAINT GREEN (-6027 2500);
DISPLAY INVISIBLE (-6027 2500);
FORCEADD TAP..6
(-6025 2400);
FORCEPROP 3 LASTPIN (-5975 2400) SIG_NAME P5E_CPU1_P3_RX_DN<7>
J 0
(-5965 2410);
DISPLAY 0.659574 (-5965 2410);
PAINT MONO (-5965 2410);
DISPLAY INVISIBLE (-5965 2410);
FORCEPROP 1 LASTPIN (-5975 2400) BN 7
J 0
(-6027 2408);
DISPLAY 0.489362 (-6027 2408);
PAINT MONO (-6027 2408);
FORCEPROP 2 LAST CDS_LIB mstr_standard
J 0
(-6025 2400);
DISPLAY INVISIBLE (-6025 2400);
FORCEPROP 1 LAST BODY_TYPE PLUMBING
J 0
(-6025 2350);
DISPLAY 0.574468 (-6025 2350);
PAINT GREEN (-6025 2350);
DISPLAY INVISIBLE (-6025 2350);
FORCEPROP 1 LAST HDL_TAP TRUE
J 0
(-5700 2275);
DISPLAY 0.574468 (-5700 2275);
PAINT GREEN (-5700 2275);
DISPLAY INVISIBLE (-5700 2275);
FORCEPROP 1 LAST PATH I310
J 0
(-6027 2400);
DISPLAY 0.872340 (-6027 2400);
PAINT GREEN (-6027 2400);
DISPLAY INVISIBLE (-6027 2400);
FORCEADD TAP..6
(-6025 2200);
FORCEPROP 3 LASTPIN (-5975 2200) SIG_NAME P5E_CPU1_P3_RX_DN<9>
J 0
(-5965 2210);
DISPLAY 0.659574 (-5965 2210);
PAINT MONO (-5965 2210);
DISPLAY INVISIBLE (-5965 2210);
FORCEPROP 1 LASTPIN (-5975 2200) BN 9
J 0
(-6027 2208);
DISPLAY 0.489362 (-6027 2208);
PAINT MONO (-6027 2208);
FORCEPROP 2 LAST CDS_LIB standard
J 0
(-6025 2200);
DISPLAY INVISIBLE (-6025 2200);
FORCEPROP 1 LAST BODY_TYPE PLUMBING
J 0
(-6025 2150);
DISPLAY 0.574468 (-6025 2150);
PAINT GREEN (-6025 2150);
DISPLAY INVISIBLE (-6025 2150);
FORCEPROP 1 LAST HDL_TAP TRUE
J 0
(-5700 2075);
DISPLAY 0.574468 (-5700 2075);
PAINT GREEN (-5700 2075);
DISPLAY INVISIBLE (-5700 2075);
FORCEPROP 1 LAST PATH I311
J 0
(-6027 2200);
DISPLAY 0.872340 (-6027 2200);
PAINT GREEN (-6027 2200);
DISPLAY INVISIBLE (-6027 2200);
FORCEADD TAP..6
(-6025 2300);
FORCEPROP 3 LASTPIN (-5975 2300) SIG_NAME P5E_CPU1_P3_RX_DN<8>
J 0
(-5965 2310);
DISPLAY 0.659574 (-5965 2310);
PAINT MONO (-5965 2310);
DISPLAY INVISIBLE (-5965 2310);
FORCEPROP 1 LASTPIN (-5975 2300) BN 8
J 0
(-6027 2308);
DISPLAY 0.489362 (-6027 2308);
PAINT MONO (-6027 2308);
FORCEPROP 2 LAST CDS_LIB mstr_standard
J 0
(-6025 2300);
DISPLAY INVISIBLE (-6025 2300);
FORCEPROP 1 LAST BODY_TYPE PLUMBING
J 0
(-6025 2250);
DISPLAY 0.574468 (-6025 2250);
PAINT GREEN (-6025 2250);
DISPLAY INVISIBLE (-6025 2250);
FORCEPROP 1 LAST HDL_TAP TRUE
J 0
(-5700 2175);
DISPLAY 0.574468 (-5700 2175);
PAINT GREEN (-5700 2175);
DISPLAY INVISIBLE (-5700 2175);
FORCEPROP 1 LAST PATH I312
J 0
(-6027 2300);
DISPLAY 0.872340 (-6027 2300);
PAINT GREEN (-6027 2300);
DISPLAY INVISIBLE (-6027 2300);
FORCEADD TAP..6
(-6025 2100);
FORCEPROP 3 LASTPIN (-5975 2100) SIG_NAME P5E_CPU1_P3_RX_DN<10>
J 0
(-5965 2110);
DISPLAY 0.659574 (-5965 2110);
PAINT MONO (-5965 2110);
DISPLAY INVISIBLE (-5965 2110);
FORCEPROP 1 LASTPIN (-5975 2100) BN 10
J 0
(-6027 2108);
DISPLAY 0.489362 (-6027 2108);
PAINT MONO (-6027 2108);
FORCEPROP 2 LAST CDS_LIB standard
J 0
(-6025 2100);
DISPLAY INVISIBLE (-6025 2100);
FORCEPROP 1 LAST BODY_TYPE PLUMBING
J 0
(-6025 2050);
DISPLAY 0.574468 (-6025 2050);
PAINT GREEN (-6025 2050);
DISPLAY INVISIBLE (-6025 2050);
FORCEPROP 1 LAST HDL_TAP TRUE
J 0
(-5700 1975);
DISPLAY 0.574468 (-5700 1975);
PAINT GREEN (-5700 1975);
DISPLAY INVISIBLE (-5700 1975);
FORCEPROP 1 LAST PATH I313
J 0
(-6027 2100);
DISPLAY 0.872340 (-6027 2100);
PAINT GREEN (-6027 2100);
DISPLAY INVISIBLE (-6027 2100);
FORCEADD TAP..6
(-6025 2000);
FORCEPROP 3 LASTPIN (-5975 2000) SIG_NAME P5E_CPU1_P3_RX_DN<11>
J 0
(-5965 2010);
DISPLAY 0.659574 (-5965 2010);
PAINT MONO (-5965 2010);
DISPLAY INVISIBLE (-5965 2010);
FORCEPROP 1 LASTPIN (-5975 2000) BN 11
J 0
(-6027 2008);
DISPLAY 0.489362 (-6027 2008);
PAINT MONO (-6027 2008);
FORCEPROP 2 LAST CDS_LIB standard
J 0
(-6025 2000);
DISPLAY INVISIBLE (-6025 2000);
FORCEPROP 1 LAST BODY_TYPE PLUMBING
J 0
(-6025 1950);
DISPLAY 0.574468 (-6025 1950);
PAINT GREEN (-6025 1950);
DISPLAY INVISIBLE (-6025 1950);
FORCEPROP 1 LAST HDL_TAP TRUE
J 0
(-5700 1875);
DISPLAY 0.574468 (-5700 1875);
PAINT GREEN (-5700 1875);
DISPLAY INVISIBLE (-5700 1875);
FORCEPROP 1 LAST PATH I314
J 0
(-6027 2000);
DISPLAY 0.872340 (-6027 2000);
PAINT GREEN (-6027 2000);
DISPLAY INVISIBLE (-6027 2000);
FORCEADD TAP..6
(-6025 1900);
FORCEPROP 3 LASTPIN (-5975 1900) SIG_NAME P5E_CPU1_P3_RX_DN<12>
J 0
(-5965 1910);
DISPLAY 0.659574 (-5965 1910);
PAINT MONO (-5965 1910);
DISPLAY INVISIBLE (-5965 1910);
FORCEPROP 1 LASTPIN (-5975 1900) BN 12
J 0
(-6027 1908);
DISPLAY 0.489362 (-6027 1908);
PAINT MONO (-6027 1908);
FORCEPROP 2 LAST CDS_LIB standard
J 0
(-6025 1900);
DISPLAY INVISIBLE (-6025 1900);
FORCEPROP 1 LAST BODY_TYPE PLUMBING
J 0
(-6025 1850);
DISPLAY 0.574468 (-6025 1850);
PAINT GREEN (-6025 1850);
DISPLAY INVISIBLE (-6025 1850);
FORCEPROP 1 LAST HDL_TAP TRUE
J 0
(-5700 1775);
DISPLAY 0.574468 (-5700 1775);
PAINT GREEN (-5700 1775);
DISPLAY INVISIBLE (-5700 1775);
FORCEPROP 1 LAST PATH I315
J 0
(-6027 1900);
DISPLAY 0.872340 (-6027 1900);
PAINT GREEN (-6027 1900);
DISPLAY INVISIBLE (-6027 1900);
FORCEADD TAP..6
(-6025 1800);
FORCEPROP 3 LASTPIN (-5975 1800) SIG_NAME P5E_CPU1_P3_RX_DN<13>
J 0
(-5965 1810);
DISPLAY 0.659574 (-5965 1810);
PAINT MONO (-5965 1810);
DISPLAY INVISIBLE (-5965 1810);
FORCEPROP 1 LASTPIN (-5975 1800) BN 13
J 0
(-6027 1808);
DISPLAY 0.489362 (-6027 1808);
PAINT MONO (-6027 1808);
FORCEPROP 2 LAST CDS_LIB standard
J 0
(-6025 1800);
DISPLAY INVISIBLE (-6025 1800);
FORCEPROP 1 LAST BODY_TYPE PLUMBING
J 0
(-6025 1750);
DISPLAY 0.574468 (-6025 1750);
PAINT GREEN (-6025 1750);
DISPLAY INVISIBLE (-6025 1750);
FORCEPROP 1 LAST HDL_TAP TRUE
J 0
(-5700 1675);
DISPLAY 0.574468 (-5700 1675);
PAINT GREEN (-5700 1675);
DISPLAY INVISIBLE (-5700 1675);
FORCEPROP 1 LAST PATH I316
J 0
(-6027 1800);
DISPLAY 0.872340 (-6027 1800);
PAINT GREEN (-6027 1800);
DISPLAY INVISIBLE (-6027 1800);
FORCEADD TAP..6
(-6025 1700);
FORCEPROP 3 LASTPIN (-5975 1700) SIG_NAME P5E_CPU1_P3_RX_DN<14>
J 0
(-5965 1710);
DISPLAY 0.659574 (-5965 1710);
PAINT MONO (-5965 1710);
DISPLAY INVISIBLE (-5965 1710);
FORCEPROP 1 LASTPIN (-5975 1700) BN 14
J 0
(-6027 1708);
DISPLAY 0.489362 (-6027 1708);
PAINT MONO (-6027 1708);
FORCEPROP 2 LAST CDS_LIB standard
J 0
(-6025 1700);
DISPLAY INVISIBLE (-6025 1700);
FORCEPROP 1 LAST BODY_TYPE PLUMBING
J 0
(-6025 1650);
DISPLAY 0.574468 (-6025 1650);
PAINT GREEN (-6025 1650);
DISPLAY INVISIBLE (-6025 1650);
FORCEPROP 1 LAST HDL_TAP TRUE
J 0
(-5700 1575);
DISPLAY 0.574468 (-5700 1575);
PAINT GREEN (-5700 1575);
DISPLAY INVISIBLE (-5700 1575);
FORCEPROP 1 LAST PATH I317
J 0
(-6027 1700);
DISPLAY 0.872340 (-6027 1700);
PAINT GREEN (-6027 1700);
DISPLAY INVISIBLE (-6027 1700);
FORCEADD TAP..6
(-6025 1600);
FORCEPROP 3 LASTPIN (-5975 1600) SIG_NAME P5E_CPU1_P3_RX_DN<15>
J 0
(-5965 1610);
DISPLAY 0.659574 (-5965 1610);
PAINT MONO (-5965 1610);
DISPLAY INVISIBLE (-5965 1610);
FORCEPROP 1 LASTPIN (-5975 1600) BN 15
J 0
(-6027 1608);
DISPLAY 0.489362 (-6027 1608);
PAINT MONO (-6027 1608);
FORCEPROP 2 LAST CDS_LIB standard
J 0
(-6025 1600);
DISPLAY INVISIBLE (-6025 1600);
FORCEPROP 1 LAST BODY_TYPE PLUMBING
J 0
(-6025 1550);
DISPLAY 0.574468 (-6025 1550);
PAINT GREEN (-6025 1550);
DISPLAY INVISIBLE (-6025 1550);
FORCEPROP 1 LAST HDL_TAP TRUE
J 0
(-5700 1475);
DISPLAY 0.574468 (-5700 1475);
PAINT GREEN (-5700 1475);
DISPLAY INVISIBLE (-5700 1475);
FORCEPROP 1 LAST PATH I318
J 0
(-6027 1600);
DISPLAY 0.872340 (-6027 1600);
PAINT GREEN (-6027 1600);
DISPLAY INVISIBLE (-6027 1600);
FORCEADD OFFPAGE..1
(-7075 3375);
FORCEPROP 2 LAST $XR0 351 
J 0
(-7327 3375);
DISPLAY 0.638298 (-7327 3375);
PAINT MONO (-7327 3375);
FORCEPROP 2 LAST CDS_LIB standard
J 0
(-7075 3375);
DISPLAY INVISIBLE (-7075 3375);
FORCEPROP 1 LAST OFFPAGE TRUE
J 0
(-6750 3250);
DISPLAY 0.872340 (-6750 3250);
PAINT GREEN (-6750 3250);
DISPLAY INVISIBLE (-6750 3250);
FORCEPROP 1 LAST COMMENT_BODY TRUE
J 0
(-6950 3275);
DISPLAY 0.872340 (-6950 3275);
PAINT GREEN (-6950 3275);
DISPLAY INVISIBLE (-6950 3275);
FORCEPROP 2 LAST PATH I319
J 0
(-7025 3450);
DISPLAY 1.021277 (-7025 3450);
DISPLAY INVISIBLE (-7025 3450);
FORCEADD OFFPAGE..1
(-7075 3325);
FORCEPROP 2 LAST $XR0 351 
J 0
(-7327 3325);
DISPLAY 0.638298 (-7327 3325);
PAINT MONO (-7327 3325);
FORCEPROP 2 LAST CDS_LIB standard
J 0
(-7075 3325);
DISPLAY INVISIBLE (-7075 3325);
FORCEPROP 1 LAST OFFPAGE TRUE
J 0
(-6750 3200);
DISPLAY 0.872340 (-6750 3200);
PAINT GREEN (-6750 3200);
DISPLAY INVISIBLE (-6750 3200);
FORCEPROP 1 LAST COMMENT_BODY TRUE
J 0
(-6950 3225);
DISPLAY 0.872340 (-6950 3225);
PAINT GREEN (-6950 3225);
DISPLAY INVISIBLE (-6950 3225);
FORCEPROP 2 LAST PATH I320
J 0
(-7025 3400);
DISPLAY 1.021277 (-7025 3400);
DISPLAY INVISIBLE (-7025 3400);
FORCEADD TAP..6
(-5875 5650);
FORCEPROP 3 LASTPIN (-5825 5650) SIG_NAME P5E_CPU1_P2_RX_DP<0>
J 0
(-5815 5660);
DISPLAY 0.659574 (-5815 5660);
PAINT MONO (-5815 5660);
DISPLAY INVISIBLE (-5815 5660);
FORCEPROP 1 LASTPIN (-5825 5650) BN 0
J 0
(-5877 5658);
DISPLAY 0.489362 (-5877 5658);
PAINT MONO (-5877 5658);
FORCEPROP 2 LAST CDS_LIB mstr_standard
J 0
(-5875 5650);
DISPLAY INVISIBLE (-5875 5650);
FORCEPROP 1 LAST BODY_TYPE PLUMBING
J 0
(-5875 5600);
DISPLAY 0.574468 (-5875 5600);
PAINT GREEN (-5875 5600);
DISPLAY INVISIBLE (-5875 5600);
FORCEPROP 1 LAST HDL_TAP TRUE
J 0
(-5550 5525);
DISPLAY 0.574468 (-5550 5525);
PAINT GREEN (-5550 5525);
DISPLAY INVISIBLE (-5550 5525);
FORCEPROP 1 LAST PATH I321
J 0
(-5877 5650);
DISPLAY 0.872340 (-5877 5650);
PAINT GREEN (-5877 5650);
DISPLAY INVISIBLE (-5877 5650);
FORCEADD TAP..6
(-5875 5550);
FORCEPROP 3 LASTPIN (-5825 5550) SIG_NAME P5E_CPU1_P2_RX_DP<1>
J 0
(-5815 5560);
DISPLAY 0.659574 (-5815 5560);
PAINT MONO (-5815 5560);
DISPLAY INVISIBLE (-5815 5560);
FORCEPROP 1 LASTPIN (-5825 5550) BN 1
J 0
(-5877 5558);
DISPLAY 0.489362 (-5877 5558);
PAINT MONO (-5877 5558);
FORCEPROP 2 LAST CDS_LIB mstr_standard
J 0
(-5875 5550);
DISPLAY INVISIBLE (-5875 5550);
FORCEPROP 1 LAST BODY_TYPE PLUMBING
J 0
(-5875 5500);
DISPLAY 0.574468 (-5875 5500);
PAINT GREEN (-5875 5500);
DISPLAY INVISIBLE (-5875 5500);
FORCEPROP 1 LAST HDL_TAP TRUE
J 0
(-5550 5425);
DISPLAY 0.574468 (-5550 5425);
PAINT GREEN (-5550 5425);
DISPLAY INVISIBLE (-5550 5425);
FORCEPROP 1 LAST PATH I322
J 0
(-5877 5550);
DISPLAY 0.872340 (-5877 5550);
PAINT GREEN (-5877 5550);
DISPLAY INVISIBLE (-5877 5550);
FORCEADD TAP..6
(-5875 5450);
FORCEPROP 3 LASTPIN (-5825 5450) SIG_NAME P5E_CPU1_P2_RX_DP<2>
J 0
(-5815 5460);
DISPLAY 0.659574 (-5815 5460);
PAINT MONO (-5815 5460);
DISPLAY INVISIBLE (-5815 5460);
FORCEPROP 1 LASTPIN (-5825 5450) BN 2
J 0
(-5877 5458);
DISPLAY 0.489362 (-5877 5458);
PAINT MONO (-5877 5458);
FORCEPROP 2 LAST CDS_LIB mstr_standard
J 0
(-5875 5450);
DISPLAY INVISIBLE (-5875 5450);
FORCEPROP 1 LAST BODY_TYPE PLUMBING
J 0
(-5875 5400);
DISPLAY 0.574468 (-5875 5400);
PAINT GREEN (-5875 5400);
DISPLAY INVISIBLE (-5875 5400);
FORCEPROP 1 LAST HDL_TAP TRUE
J 0
(-5550 5325);
DISPLAY 0.574468 (-5550 5325);
PAINT GREEN (-5550 5325);
DISPLAY INVISIBLE (-5550 5325);
FORCEPROP 1 LAST PATH I323
J 0
(-5877 5450);
DISPLAY 0.872340 (-5877 5450);
PAINT GREEN (-5877 5450);
DISPLAY INVISIBLE (-5877 5450);
FORCEADD TAP..6
(-6025 5600);
FORCEPROP 3 LASTPIN (-5975 5600) SIG_NAME P5E_CPU1_P2_RX_DN<0>
J 0
(-5965 5610);
DISPLAY 0.659574 (-5965 5610);
PAINT MONO (-5965 5610);
DISPLAY INVISIBLE (-5965 5610);
FORCEPROP 1 LASTPIN (-5975 5600) BN 0
J 0
(-6027 5608);
DISPLAY 0.489362 (-6027 5608);
PAINT MONO (-6027 5608);
FORCEPROP 2 LAST CDS_LIB mstr_standard
J 0
(-6025 5600);
DISPLAY INVISIBLE (-6025 5600);
FORCEPROP 1 LAST BODY_TYPE PLUMBING
J 0
(-6025 5550);
DISPLAY 0.574468 (-6025 5550);
PAINT GREEN (-6025 5550);
DISPLAY INVISIBLE (-6025 5550);
FORCEPROP 1 LAST HDL_TAP TRUE
J 0
(-5700 5475);
DISPLAY 0.574468 (-5700 5475);
PAINT GREEN (-5700 5475);
DISPLAY INVISIBLE (-5700 5475);
FORCEPROP 1 LAST PATH I324
J 0
(-6027 5600);
DISPLAY 0.872340 (-6027 5600);
PAINT GREEN (-6027 5600);
DISPLAY INVISIBLE (-6027 5600);
FORCEADD TAP..6
(-6025 5500);
FORCEPROP 3 LASTPIN (-5975 5500) SIG_NAME P5E_CPU1_P2_RX_DN<1>
J 0
(-5965 5510);
DISPLAY 0.659574 (-5965 5510);
PAINT MONO (-5965 5510);
DISPLAY INVISIBLE (-5965 5510);
FORCEPROP 1 LASTPIN (-5975 5500) BN 1
J 0
(-6027 5508);
DISPLAY 0.489362 (-6027 5508);
PAINT MONO (-6027 5508);
FORCEPROP 2 LAST CDS_LIB mstr_standard
J 0
(-6025 5500);
DISPLAY INVISIBLE (-6025 5500);
FORCEPROP 1 LAST BODY_TYPE PLUMBING
J 0
(-6025 5450);
DISPLAY 0.574468 (-6025 5450);
PAINT GREEN (-6025 5450);
DISPLAY INVISIBLE (-6025 5450);
FORCEPROP 1 LAST HDL_TAP TRUE
J 0
(-5700 5375);
DISPLAY 0.574468 (-5700 5375);
PAINT GREEN (-5700 5375);
DISPLAY INVISIBLE (-5700 5375);
FORCEPROP 1 LAST PATH I325
J 0
(-6027 5500);
DISPLAY 0.872340 (-6027 5500);
PAINT GREEN (-6027 5500);
DISPLAY INVISIBLE (-6027 5500);
FORCEADD TAP..6
(-6025 5400);
FORCEPROP 3 LASTPIN (-5975 5400) SIG_NAME P5E_CPU1_P2_RX_DN<2>
J 0
(-5965 5410);
DISPLAY 0.659574 (-5965 5410);
PAINT MONO (-5965 5410);
DISPLAY INVISIBLE (-5965 5410);
FORCEPROP 1 LASTPIN (-5975 5400) BN 2
J 0
(-6027 5408);
DISPLAY 0.489362 (-6027 5408);
PAINT MONO (-6027 5408);
FORCEPROP 2 LAST CDS_LIB standard
J 0
(-6025 5400);
DISPLAY INVISIBLE (-6025 5400);
FORCEPROP 1 LAST BODY_TYPE PLUMBING
J 0
(-6025 5350);
DISPLAY 0.574468 (-6025 5350);
PAINT GREEN (-6025 5350);
DISPLAY INVISIBLE (-6025 5350);
FORCEPROP 1 LAST HDL_TAP TRUE
J 0
(-5700 5275);
DISPLAY 0.574468 (-5700 5275);
PAINT GREEN (-5700 5275);
DISPLAY INVISIBLE (-5700 5275);
FORCEPROP 1 LAST PATH I326
J 0
(-6027 5400);
DISPLAY 0.872340 (-6027 5400);
PAINT GREEN (-6027 5400);
DISPLAY INVISIBLE (-6027 5400);
FORCEADD TAP..6
(-5875 5150);
FORCEPROP 3 LASTPIN (-5825 5150) SIG_NAME P5E_CPU1_P2_RX_DP<5>
J 0
(-5815 5160);
DISPLAY 0.659574 (-5815 5160);
PAINT MONO (-5815 5160);
DISPLAY INVISIBLE (-5815 5160);
FORCEPROP 1 LASTPIN (-5825 5150) BN 5
J 0
(-5877 5158);
DISPLAY 0.489362 (-5877 5158);
PAINT MONO (-5877 5158);
FORCEPROP 2 LAST CDS_LIB standard
J 0
(-5875 5150);
DISPLAY INVISIBLE (-5875 5150);
FORCEPROP 1 LAST BODY_TYPE PLUMBING
J 0
(-5875 5100);
DISPLAY 0.574468 (-5875 5100);
PAINT GREEN (-5875 5100);
DISPLAY INVISIBLE (-5875 5100);
FORCEPROP 1 LAST HDL_TAP TRUE
J 0
(-5550 5025);
DISPLAY 0.574468 (-5550 5025);
PAINT GREEN (-5550 5025);
DISPLAY INVISIBLE (-5550 5025);
FORCEPROP 1 LAST PATH I327
J 0
(-5877 5150);
DISPLAY 0.872340 (-5877 5150);
PAINT GREEN (-5877 5150);
DISPLAY INVISIBLE (-5877 5150);
FORCEADD TAP..6
(-5875 5350);
FORCEPROP 3 LASTPIN (-5825 5350) SIG_NAME P5E_CPU1_P2_RX_DP<3>
J 0
(-5815 5360);
DISPLAY 0.659574 (-5815 5360);
PAINT MONO (-5815 5360);
DISPLAY INVISIBLE (-5815 5360);
FORCEPROP 1 LASTPIN (-5825 5350) BN 3
J 0
(-5877 5358);
DISPLAY 0.489362 (-5877 5358);
PAINT MONO (-5877 5358);
FORCEPROP 2 LAST CDS_LIB standard
J 0
(-5875 5350);
DISPLAY INVISIBLE (-5875 5350);
FORCEPROP 1 LAST BODY_TYPE PLUMBING
J 0
(-5875 5300);
DISPLAY 0.574468 (-5875 5300);
PAINT GREEN (-5875 5300);
DISPLAY INVISIBLE (-5875 5300);
FORCEPROP 1 LAST HDL_TAP TRUE
J 0
(-5550 5225);
DISPLAY 0.574468 (-5550 5225);
PAINT GREEN (-5550 5225);
DISPLAY INVISIBLE (-5550 5225);
FORCEPROP 1 LAST PATH I328
J 0
(-5877 5350);
DISPLAY 0.872340 (-5877 5350);
PAINT GREEN (-5877 5350);
DISPLAY INVISIBLE (-5877 5350);
FORCEADD TAP..6
(-5875 5250);
FORCEPROP 3 LASTPIN (-5825 5250) SIG_NAME P5E_CPU1_P2_RX_DP<4>
J 0
(-5815 5260);
DISPLAY 0.659574 (-5815 5260);
PAINT MONO (-5815 5260);
DISPLAY INVISIBLE (-5815 5260);
FORCEPROP 1 LASTPIN (-5825 5250) BN 4
J 0
(-5877 5258);
DISPLAY 0.489362 (-5877 5258);
PAINT MONO (-5877 5258);
FORCEPROP 2 LAST CDS_LIB standard
J 0
(-5875 5250);
DISPLAY INVISIBLE (-5875 5250);
FORCEPROP 1 LAST BODY_TYPE PLUMBING
J 0
(-5875 5200);
DISPLAY 0.574468 (-5875 5200);
PAINT GREEN (-5875 5200);
DISPLAY INVISIBLE (-5875 5200);
FORCEPROP 1 LAST HDL_TAP TRUE
J 0
(-5550 5125);
DISPLAY 0.574468 (-5550 5125);
PAINT GREEN (-5550 5125);
DISPLAY INVISIBLE (-5550 5125);
FORCEPROP 1 LAST PATH I329
J 0
(-5877 5250);
DISPLAY 0.872340 (-5877 5250);
PAINT GREEN (-5877 5250);
DISPLAY INVISIBLE (-5877 5250);
FORCEADD TAP..6
(-6025 5200);
FORCEPROP 3 LASTPIN (-5975 5200) SIG_NAME P5E_CPU1_P2_RX_DN<4>
J 0
(-5965 5210);
DISPLAY 0.659574 (-5965 5210);
PAINT MONO (-5965 5210);
DISPLAY INVISIBLE (-5965 5210);
FORCEPROP 1 LASTPIN (-5975 5200) BN 4
J 0
(-6027 5208);
DISPLAY 0.489362 (-6027 5208);
PAINT MONO (-6027 5208);
FORCEPROP 2 LAST CDS_LIB standard
J 0
(-6025 5200);
DISPLAY INVISIBLE (-6025 5200);
FORCEPROP 1 LAST BODY_TYPE PLUMBING
J 0
(-6025 5150);
DISPLAY 0.574468 (-6025 5150);
PAINT GREEN (-6025 5150);
DISPLAY INVISIBLE (-6025 5150);
FORCEPROP 1 LAST HDL_TAP TRUE
J 0
(-5700 5075);
DISPLAY 0.574468 (-5700 5075);
PAINT GREEN (-5700 5075);
DISPLAY INVISIBLE (-5700 5075);
FORCEPROP 1 LAST PATH I330
J 0
(-6027 5200);
DISPLAY 0.872340 (-6027 5200);
PAINT GREEN (-6027 5200);
DISPLAY INVISIBLE (-6027 5200);
FORCEADD TAP..6
(-6025 5300);
FORCEPROP 3 LASTPIN (-5975 5300) SIG_NAME P5E_CPU1_P2_RX_DN<3>
J 0
(-5965 5310);
DISPLAY 0.659574 (-5965 5310);
PAINT MONO (-5965 5310);
DISPLAY INVISIBLE (-5965 5310);
FORCEPROP 1 LASTPIN (-5975 5300) BN 3
J 0
(-6027 5308);
DISPLAY 0.489362 (-6027 5308);
PAINT MONO (-6027 5308);
FORCEPROP 2 LAST CDS_LIB standard
J 0
(-6025 5300);
DISPLAY INVISIBLE (-6025 5300);
FORCEPROP 1 LAST BODY_TYPE PLUMBING
J 0
(-6025 5250);
DISPLAY 0.574468 (-6025 5250);
PAINT GREEN (-6025 5250);
DISPLAY INVISIBLE (-6025 5250);
FORCEPROP 1 LAST HDL_TAP TRUE
J 0
(-5700 5175);
DISPLAY 0.574468 (-5700 5175);
PAINT GREEN (-5700 5175);
DISPLAY INVISIBLE (-5700 5175);
FORCEPROP 1 LAST PATH I331
J 0
(-6027 5300);
DISPLAY 0.872340 (-6027 5300);
PAINT GREEN (-6027 5300);
DISPLAY INVISIBLE (-6027 5300);
FORCEADD TAP..6
(-5875 5050);
FORCEPROP 3 LASTPIN (-5825 5050) SIG_NAME P5E_CPU1_P2_RX_DP<6>
J 0
(-5815 5060);
DISPLAY 0.659574 (-5815 5060);
PAINT MONO (-5815 5060);
DISPLAY INVISIBLE (-5815 5060);
FORCEPROP 1 LASTPIN (-5825 5050) BN 6
J 0
(-5877 5058);
DISPLAY 0.489362 (-5877 5058);
PAINT MONO (-5877 5058);
FORCEPROP 2 LAST CDS_LIB standard
J 0
(-5875 5050);
DISPLAY INVISIBLE (-5875 5050);
FORCEPROP 1 LAST BODY_TYPE PLUMBING
J 0
(-5875 5000);
DISPLAY 0.574468 (-5875 5000);
PAINT GREEN (-5875 5000);
DISPLAY INVISIBLE (-5875 5000);
FORCEPROP 1 LAST HDL_TAP TRUE
J 0
(-5550 4925);
DISPLAY 0.574468 (-5550 4925);
PAINT GREEN (-5550 4925);
DISPLAY INVISIBLE (-5550 4925);
FORCEPROP 1 LAST PATH I332
J 0
(-5877 5050);
DISPLAY 0.872340 (-5877 5050);
PAINT GREEN (-5877 5050);
DISPLAY INVISIBLE (-5877 5050);
FORCEADD TAP..6
(-5875 4850);
FORCEPROP 3 LASTPIN (-5825 4850) SIG_NAME P5E_CPU1_P2_RX_DP<8>
J 0
(-5815 4860);
DISPLAY 0.659574 (-5815 4860);
PAINT MONO (-5815 4860);
DISPLAY INVISIBLE (-5815 4860);
FORCEPROP 1 LASTPIN (-5825 4850) BN 8
J 0
(-5877 4858);
DISPLAY 0.489362 (-5877 4858);
PAINT MONO (-5877 4858);
FORCEPROP 2 LAST CDS_LIB standard
J 0
(-5875 4850);
DISPLAY INVISIBLE (-5875 4850);
FORCEPROP 1 LAST BODY_TYPE PLUMBING
J 0
(-5875 4800);
DISPLAY 0.574468 (-5875 4800);
PAINT GREEN (-5875 4800);
DISPLAY INVISIBLE (-5875 4800);
FORCEPROP 1 LAST HDL_TAP TRUE
J 0
(-5550 4725);
DISPLAY 0.574468 (-5550 4725);
PAINT GREEN (-5550 4725);
DISPLAY INVISIBLE (-5550 4725);
FORCEPROP 1 LAST PATH I333
J 0
(-5877 4850);
DISPLAY 0.872340 (-5877 4850);
PAINT GREEN (-5877 4850);
DISPLAY INVISIBLE (-5877 4850);
FORCEADD TAP..6
(-5875 4950);
FORCEPROP 3 LASTPIN (-5825 4950) SIG_NAME P5E_CPU1_P2_RX_DP<7>
J 0
(-5815 4960);
DISPLAY 0.659574 (-5815 4960);
PAINT MONO (-5815 4960);
DISPLAY INVISIBLE (-5815 4960);
FORCEPROP 1 LASTPIN (-5825 4950) BN 7
J 0
(-5877 4958);
DISPLAY 0.489362 (-5877 4958);
PAINT MONO (-5877 4958);
FORCEPROP 2 LAST CDS_LIB standard
J 0
(-5875 4950);
DISPLAY INVISIBLE (-5875 4950);
FORCEPROP 1 LAST BODY_TYPE PLUMBING
J 0
(-5875 4900);
DISPLAY 0.574468 (-5875 4900);
PAINT GREEN (-5875 4900);
DISPLAY INVISIBLE (-5875 4900);
FORCEPROP 1 LAST HDL_TAP TRUE
J 0
(-5550 4825);
DISPLAY 0.574468 (-5550 4825);
PAINT GREEN (-5550 4825);
DISPLAY INVISIBLE (-5550 4825);
FORCEPROP 1 LAST PATH I334
J 0
(-5877 4950);
DISPLAY 0.872340 (-5877 4950);
PAINT GREEN (-5877 4950);
DISPLAY INVISIBLE (-5877 4950);
FORCEADD TAP..6
(-6025 4900);
FORCEPROP 3 LASTPIN (-5975 4900) SIG_NAME P5E_CPU1_P2_RX_DN<7>
J 0
(-5965 4910);
DISPLAY 0.659574 (-5965 4910);
PAINT MONO (-5965 4910);
DISPLAY INVISIBLE (-5965 4910);
FORCEPROP 1 LASTPIN (-5975 4900) BN 7
J 0
(-6027 4908);
DISPLAY 0.489362 (-6027 4908);
PAINT MONO (-6027 4908);
FORCEPROP 2 LAST CDS_LIB standard
J 0
(-6025 4900);
DISPLAY INVISIBLE (-6025 4900);
FORCEPROP 1 LAST BODY_TYPE PLUMBING
J 0
(-6025 4850);
DISPLAY 0.574468 (-6025 4850);
PAINT GREEN (-6025 4850);
DISPLAY INVISIBLE (-6025 4850);
FORCEPROP 1 LAST HDL_TAP TRUE
J 0
(-5700 4775);
DISPLAY 0.574468 (-5700 4775);
PAINT GREEN (-5700 4775);
DISPLAY INVISIBLE (-5700 4775);
FORCEPROP 1 LAST PATH I335
J 0
(-6027 4900);
DISPLAY 0.872340 (-6027 4900);
PAINT GREEN (-6027 4900);
DISPLAY INVISIBLE (-6027 4900);
FORCEADD TAP..6
(-6025 5000);
FORCEPROP 3 LASTPIN (-5975 5000) SIG_NAME P5E_CPU1_P2_RX_DN<6>
J 0
(-5965 5010);
DISPLAY 0.659574 (-5965 5010);
PAINT MONO (-5965 5010);
DISPLAY INVISIBLE (-5965 5010);
FORCEPROP 1 LASTPIN (-5975 5000) BN 6
J 0
(-6027 5008);
DISPLAY 0.489362 (-6027 5008);
PAINT MONO (-6027 5008);
FORCEPROP 2 LAST CDS_LIB standard
J 0
(-6025 5000);
DISPLAY INVISIBLE (-6025 5000);
FORCEPROP 1 LAST BODY_TYPE PLUMBING
J 0
(-6025 4950);
DISPLAY 0.574468 (-6025 4950);
PAINT GREEN (-6025 4950);
DISPLAY INVISIBLE (-6025 4950);
FORCEPROP 1 LAST HDL_TAP TRUE
J 0
(-5700 4875);
DISPLAY 0.574468 (-5700 4875);
PAINT GREEN (-5700 4875);
DISPLAY INVISIBLE (-5700 4875);
FORCEPROP 1 LAST PATH I336
J 0
(-6027 5000);
DISPLAY 0.872340 (-6027 5000);
PAINT GREEN (-6027 5000);
DISPLAY INVISIBLE (-6027 5000);
FORCEADD TAP..6
(-6025 5100);
FORCEPROP 3 LASTPIN (-5975 5100) SIG_NAME P5E_CPU1_P2_RX_DN<5>
J 0
(-5965 5110);
DISPLAY 0.659574 (-5965 5110);
PAINT MONO (-5965 5110);
DISPLAY INVISIBLE (-5965 5110);
FORCEPROP 1 LASTPIN (-5975 5100) BN 5
J 0
(-6027 5108);
DISPLAY 0.489362 (-6027 5108);
PAINT MONO (-6027 5108);
FORCEPROP 2 LAST CDS_LIB standard
J 0
(-6025 5100);
DISPLAY INVISIBLE (-6025 5100);
FORCEPROP 1 LAST BODY_TYPE PLUMBING
J 0
(-6025 5050);
DISPLAY 0.574468 (-6025 5050);
PAINT GREEN (-6025 5050);
DISPLAY INVISIBLE (-6025 5050);
FORCEPROP 1 LAST HDL_TAP TRUE
J 0
(-5700 4975);
DISPLAY 0.574468 (-5700 4975);
PAINT GREEN (-5700 4975);
DISPLAY INVISIBLE (-5700 4975);
FORCEPROP 1 LAST PATH I337
J 0
(-6027 5100);
DISPLAY 0.872340 (-6027 5100);
PAINT GREEN (-6027 5100);
DISPLAY INVISIBLE (-6027 5100);
FORCEADD TAP..6
(-5875 4750);
FORCEPROP 3 LASTPIN (-5825 4750) SIG_NAME P5E_CPU1_P2_RX_DP<9>
J 0
(-5815 4760);
DISPLAY 0.659574 (-5815 4760);
PAINT MONO (-5815 4760);
DISPLAY INVISIBLE (-5815 4760);
FORCEPROP 1 LASTPIN (-5825 4750) BN 9
J 0
(-5877 4758);
DISPLAY 0.489362 (-5877 4758);
PAINT MONO (-5877 4758);
FORCEPROP 2 LAST CDS_LIB standard
J 0
(-5875 4750);
DISPLAY INVISIBLE (-5875 4750);
FORCEPROP 1 LAST BODY_TYPE PLUMBING
J 0
(-5875 4700);
DISPLAY 0.574468 (-5875 4700);
PAINT GREEN (-5875 4700);
DISPLAY INVISIBLE (-5875 4700);
FORCEPROP 1 LAST HDL_TAP TRUE
J 0
(-5550 4625);
DISPLAY 0.574468 (-5550 4625);
PAINT GREEN (-5550 4625);
DISPLAY INVISIBLE (-5550 4625);
FORCEPROP 1 LAST PATH I338
J 0
(-5877 4750);
DISPLAY 0.872340 (-5877 4750);
PAINT GREEN (-5877 4750);
DISPLAY INVISIBLE (-5877 4750);
FORCEADD TAP..6
(-5875 4650);
FORCEPROP 3 LASTPIN (-5825 4650) SIG_NAME P5E_CPU1_P2_RX_DP<10>
J 0
(-5815 4660);
DISPLAY 0.659574 (-5815 4660);
PAINT MONO (-5815 4660);
DISPLAY INVISIBLE (-5815 4660);
FORCEPROP 1 LASTPIN (-5825 4650) BN 10
J 0
(-5877 4658);
DISPLAY 0.489362 (-5877 4658);
PAINT MONO (-5877 4658);
FORCEPROP 2 LAST CDS_LIB standard
J 0
(-5875 4650);
DISPLAY INVISIBLE (-5875 4650);
FORCEPROP 1 LAST BODY_TYPE PLUMBING
J 0
(-5875 4600);
DISPLAY 0.574468 (-5875 4600);
PAINT GREEN (-5875 4600);
DISPLAY INVISIBLE (-5875 4600);
FORCEPROP 1 LAST HDL_TAP TRUE
J 0
(-5550 4525);
DISPLAY 0.574468 (-5550 4525);
PAINT GREEN (-5550 4525);
DISPLAY INVISIBLE (-5550 4525);
FORCEPROP 1 LAST PATH I339
J 0
(-5877 4650);
DISPLAY 0.872340 (-5877 4650);
PAINT GREEN (-5877 4650);
DISPLAY INVISIBLE (-5877 4650);
FORCEADD TAP..6
(-6025 4700);
FORCEPROP 3 LASTPIN (-5975 4700) SIG_NAME P5E_CPU1_P2_RX_DN<9>
J 0
(-5965 4710);
DISPLAY 0.659574 (-5965 4710);
PAINT MONO (-5965 4710);
DISPLAY INVISIBLE (-5965 4710);
FORCEPROP 1 LASTPIN (-5975 4700) BN 9
J 0
(-6027 4708);
DISPLAY 0.489362 (-6027 4708);
PAINT MONO (-6027 4708);
FORCEPROP 2 LAST CDS_LIB standard
J 0
(-6025 4700);
DISPLAY INVISIBLE (-6025 4700);
FORCEPROP 1 LAST BODY_TYPE PLUMBING
J 0
(-6025 4650);
DISPLAY 0.574468 (-6025 4650);
PAINT GREEN (-6025 4650);
DISPLAY INVISIBLE (-6025 4650);
FORCEPROP 1 LAST HDL_TAP TRUE
J 0
(-5700 4575);
DISPLAY 0.574468 (-5700 4575);
PAINT GREEN (-5700 4575);
DISPLAY INVISIBLE (-5700 4575);
FORCEPROP 1 LAST PATH I340
J 0
(-6027 4700);
DISPLAY 0.872340 (-6027 4700);
PAINT GREEN (-6027 4700);
DISPLAY INVISIBLE (-6027 4700);
FORCEADD TAP..6
(-6025 4800);
FORCEPROP 3 LASTPIN (-5975 4800) SIG_NAME P5E_CPU1_P2_RX_DN<8>
J 0
(-5965 4810);
DISPLAY 0.659574 (-5965 4810);
PAINT MONO (-5965 4810);
DISPLAY INVISIBLE (-5965 4810);
FORCEPROP 1 LASTPIN (-5975 4800) BN 8
J 0
(-6027 4808);
DISPLAY 0.489362 (-6027 4808);
PAINT MONO (-6027 4808);
FORCEPROP 2 LAST CDS_LIB standard
J 0
(-6025 4800);
DISPLAY INVISIBLE (-6025 4800);
FORCEPROP 1 LAST BODY_TYPE PLUMBING
J 0
(-6025 4750);
DISPLAY 0.574468 (-6025 4750);
PAINT GREEN (-6025 4750);
DISPLAY INVISIBLE (-6025 4750);
FORCEPROP 1 LAST HDL_TAP TRUE
J 0
(-5700 4675);
DISPLAY 0.574468 (-5700 4675);
PAINT GREEN (-5700 4675);
DISPLAY INVISIBLE (-5700 4675);
FORCEPROP 1 LAST PATH I341
J 0
(-6027 4800);
DISPLAY 0.872340 (-6027 4800);
PAINT GREEN (-6027 4800);
DISPLAY INVISIBLE (-6027 4800);
FORCEADD TAP..6
(-5875 4550);
FORCEPROP 3 LASTPIN (-5825 4550) SIG_NAME P5E_CPU1_P2_RX_DP<11>
J 0
(-5815 4560);
DISPLAY 0.659574 (-5815 4560);
PAINT MONO (-5815 4560);
DISPLAY INVISIBLE (-5815 4560);
FORCEPROP 1 LASTPIN (-5825 4550) BN 11
J 0
(-5877 4558);
DISPLAY 0.489362 (-5877 4558);
PAINT MONO (-5877 4558);
FORCEPROP 2 LAST CDS_LIB standard
J 0
(-5875 4550);
DISPLAY INVISIBLE (-5875 4550);
FORCEPROP 1 LAST BODY_TYPE PLUMBING
J 0
(-5875 4500);
DISPLAY 0.574468 (-5875 4500);
PAINT GREEN (-5875 4500);
DISPLAY INVISIBLE (-5875 4500);
FORCEPROP 1 LAST HDL_TAP TRUE
J 0
(-5550 4425);
DISPLAY 0.574468 (-5550 4425);
PAINT GREEN (-5550 4425);
DISPLAY INVISIBLE (-5550 4425);
FORCEPROP 1 LAST PATH I342
J 0
(-5877 4550);
DISPLAY 0.872340 (-5877 4550);
PAINT GREEN (-5877 4550);
DISPLAY INVISIBLE (-5877 4550);
FORCEADD TAP..6
(-5875 4350);
FORCEPROP 3 LASTPIN (-5825 4350) SIG_NAME P5E_CPU1_P2_RX_DP<13>
J 0
(-5815 4360);
DISPLAY 0.659574 (-5815 4360);
PAINT MONO (-5815 4360);
DISPLAY INVISIBLE (-5815 4360);
FORCEPROP 1 LASTPIN (-5825 4350) BN 13
J 0
(-5877 4358);
DISPLAY 0.489362 (-5877 4358);
PAINT MONO (-5877 4358);
FORCEPROP 2 LAST CDS_LIB standard
J 0
(-5875 4350);
DISPLAY INVISIBLE (-5875 4350);
FORCEPROP 1 LAST BODY_TYPE PLUMBING
J 0
(-5875 4300);
DISPLAY 0.574468 (-5875 4300);
PAINT GREEN (-5875 4300);
DISPLAY INVISIBLE (-5875 4300);
FORCEPROP 1 LAST HDL_TAP TRUE
J 0
(-5550 4225);
DISPLAY 0.574468 (-5550 4225);
PAINT GREEN (-5550 4225);
DISPLAY INVISIBLE (-5550 4225);
FORCEPROP 1 LAST PATH I343
J 0
(-5877 4350);
DISPLAY 0.872340 (-5877 4350);
PAINT GREEN (-5877 4350);
DISPLAY INVISIBLE (-5877 4350);
FORCEADD TAP..6
(-5875 4450);
FORCEPROP 3 LASTPIN (-5825 4450) SIG_NAME P5E_CPU1_P2_RX_DP<12>
J 0
(-5815 4460);
DISPLAY 0.659574 (-5815 4460);
PAINT MONO (-5815 4460);
DISPLAY INVISIBLE (-5815 4460);
FORCEPROP 1 LASTPIN (-5825 4450) BN 12
J 0
(-5877 4458);
DISPLAY 0.489362 (-5877 4458);
PAINT MONO (-5877 4458);
FORCEPROP 2 LAST CDS_LIB standard
J 0
(-5875 4450);
DISPLAY INVISIBLE (-5875 4450);
FORCEPROP 1 LAST BODY_TYPE PLUMBING
J 0
(-5875 4400);
DISPLAY 0.574468 (-5875 4400);
PAINT GREEN (-5875 4400);
DISPLAY INVISIBLE (-5875 4400);
FORCEPROP 1 LAST HDL_TAP TRUE
J 0
(-5550 4325);
DISPLAY 0.574468 (-5550 4325);
PAINT GREEN (-5550 4325);
DISPLAY INVISIBLE (-5550 4325);
FORCEPROP 1 LAST PATH I344
J 0
(-5877 4450);
DISPLAY 0.872340 (-5877 4450);
PAINT GREEN (-5877 4450);
DISPLAY INVISIBLE (-5877 4450);
FORCEADD TAP..6
(-6025 4400);
FORCEPROP 3 LASTPIN (-5975 4400) SIG_NAME P5E_CPU1_P2_RX_DN<12>
J 0
(-5965 4410);
DISPLAY 0.659574 (-5965 4410);
PAINT MONO (-5965 4410);
DISPLAY INVISIBLE (-5965 4410);
FORCEPROP 1 LASTPIN (-5975 4400) BN 12
J 0
(-6027 4408);
DISPLAY 0.489362 (-6027 4408);
PAINT MONO (-6027 4408);
FORCEPROP 2 LAST CDS_LIB standard
J 0
(-6025 4400);
DISPLAY INVISIBLE (-6025 4400);
FORCEPROP 1 LAST BODY_TYPE PLUMBING
J 0
(-6025 4350);
DISPLAY 0.574468 (-6025 4350);
PAINT GREEN (-6025 4350);
DISPLAY INVISIBLE (-6025 4350);
FORCEPROP 1 LAST HDL_TAP TRUE
J 0
(-5700 4275);
DISPLAY 0.574468 (-5700 4275);
PAINT GREEN (-5700 4275);
DISPLAY INVISIBLE (-5700 4275);
FORCEPROP 1 LAST PATH I345
J 0
(-6027 4400);
DISPLAY 0.872340 (-6027 4400);
PAINT GREEN (-6027 4400);
DISPLAY INVISIBLE (-6027 4400);
FORCEADD TAP..6
(-6025 4500);
FORCEPROP 3 LASTPIN (-5975 4500) SIG_NAME P5E_CPU1_P2_RX_DN<11>
J 0
(-5965 4510);
DISPLAY 0.659574 (-5965 4510);
PAINT MONO (-5965 4510);
DISPLAY INVISIBLE (-5965 4510);
FORCEPROP 1 LASTPIN (-5975 4500) BN 11
J 0
(-6027 4508);
DISPLAY 0.489362 (-6027 4508);
PAINT MONO (-6027 4508);
FORCEPROP 2 LAST CDS_LIB standard
J 0
(-6025 4500);
DISPLAY INVISIBLE (-6025 4500);
FORCEPROP 1 LAST BODY_TYPE PLUMBING
J 0
(-6025 4450);
DISPLAY 0.574468 (-6025 4450);
PAINT GREEN (-6025 4450);
DISPLAY INVISIBLE (-6025 4450);
FORCEPROP 1 LAST HDL_TAP TRUE
J 0
(-5700 4375);
DISPLAY 0.574468 (-5700 4375);
PAINT GREEN (-5700 4375);
DISPLAY INVISIBLE (-5700 4375);
FORCEPROP 1 LAST PATH I346
J 0
(-6027 4500);
DISPLAY 0.872340 (-6027 4500);
PAINT GREEN (-6027 4500);
DISPLAY INVISIBLE (-6027 4500);
FORCEADD TAP..6
(-6025 4600);
FORCEPROP 3 LASTPIN (-5975 4600) SIG_NAME P5E_CPU1_P2_RX_DN<10>
J 0
(-5965 4610);
DISPLAY 0.659574 (-5965 4610);
PAINT MONO (-5965 4610);
DISPLAY INVISIBLE (-5965 4610);
FORCEPROP 1 LASTPIN (-5975 4600) BN 10
J 0
(-6027 4608);
DISPLAY 0.489362 (-6027 4608);
PAINT MONO (-6027 4608);
FORCEPROP 2 LAST CDS_LIB standard
J 0
(-6025 4600);
DISPLAY INVISIBLE (-6025 4600);
FORCEPROP 1 LAST BODY_TYPE PLUMBING
J 0
(-6025 4550);
DISPLAY 0.574468 (-6025 4550);
PAINT GREEN (-6025 4550);
DISPLAY INVISIBLE (-6025 4550);
FORCEPROP 1 LAST HDL_TAP TRUE
J 0
(-5700 4475);
DISPLAY 0.574468 (-5700 4475);
PAINT GREEN (-5700 4475);
DISPLAY INVISIBLE (-5700 4475);
FORCEPROP 1 LAST PATH I347
J 0
(-6027 4600);
DISPLAY 0.872340 (-6027 4600);
PAINT GREEN (-6027 4600);
DISPLAY INVISIBLE (-6027 4600);
FORCEADD TAP..6
(-5875 4250);
FORCEPROP 3 LASTPIN (-5825 4250) SIG_NAME P5E_CPU1_P2_RX_DP<14>
J 0
(-5815 4260);
DISPLAY 0.659574 (-5815 4260);
PAINT MONO (-5815 4260);
DISPLAY INVISIBLE (-5815 4260);
FORCEPROP 1 LASTPIN (-5825 4250) BN 14
J 0
(-5877 4258);
DISPLAY 0.489362 (-5877 4258);
PAINT MONO (-5877 4258);
FORCEPROP 2 LAST CDS_LIB standard
J 0
(-5875 4250);
DISPLAY INVISIBLE (-5875 4250);
FORCEPROP 1 LAST BODY_TYPE PLUMBING
J 0
(-5875 4200);
DISPLAY 0.574468 (-5875 4200);
PAINT GREEN (-5875 4200);
DISPLAY INVISIBLE (-5875 4200);
FORCEPROP 1 LAST HDL_TAP TRUE
J 0
(-5550 4125);
DISPLAY 0.574468 (-5550 4125);
PAINT GREEN (-5550 4125);
DISPLAY INVISIBLE (-5550 4125);
FORCEPROP 1 LAST PATH I348
J 0
(-5877 4250);
DISPLAY 0.872340 (-5877 4250);
PAINT GREEN (-5877 4250);
DISPLAY INVISIBLE (-5877 4250);
FORCEADD TAP..6
(-5875 4150);
FORCEPROP 3 LASTPIN (-5825 4150) SIG_NAME P5E_CPU1_P2_RX_DP<15>
J 0
(-5815 4160);
DISPLAY 0.659574 (-5815 4160);
PAINT MONO (-5815 4160);
DISPLAY INVISIBLE (-5815 4160);
FORCEPROP 1 LASTPIN (-5825 4150) BN 15
J 0
(-5877 4158);
DISPLAY 0.489362 (-5877 4158);
PAINT MONO (-5877 4158);
FORCEPROP 2 LAST CDS_LIB standard
J 0
(-5875 4150);
DISPLAY INVISIBLE (-5875 4150);
FORCEPROP 1 LAST BODY_TYPE PLUMBING
J 0
(-5875 4100);
DISPLAY 0.574468 (-5875 4100);
PAINT GREEN (-5875 4100);
DISPLAY INVISIBLE (-5875 4100);
FORCEPROP 1 LAST HDL_TAP TRUE
J 0
(-5550 4025);
DISPLAY 0.574468 (-5550 4025);
PAINT GREEN (-5550 4025);
DISPLAY INVISIBLE (-5550 4025);
FORCEPROP 1 LAST PATH I349
J 0
(-5877 4150);
DISPLAY 0.872340 (-5877 4150);
PAINT GREEN (-5877 4150);
DISPLAY INVISIBLE (-5877 4150);
FORCEADD TAP..6
(-6025 4300);
FORCEPROP 3 LASTPIN (-5975 4300) SIG_NAME P5E_CPU1_P2_RX_DN<13>
J 0
(-5965 4310);
DISPLAY 0.659574 (-5965 4310);
PAINT MONO (-5965 4310);
DISPLAY INVISIBLE (-5965 4310);
FORCEPROP 1 LASTPIN (-5975 4300) BN 13
J 0
(-6027 4308);
DISPLAY 0.489362 (-6027 4308);
PAINT MONO (-6027 4308);
FORCEPROP 2 LAST CDS_LIB standard
J 0
(-6025 4300);
DISPLAY INVISIBLE (-6025 4300);
FORCEPROP 1 LAST BODY_TYPE PLUMBING
J 0
(-6025 4250);
DISPLAY 0.574468 (-6025 4250);
PAINT GREEN (-6025 4250);
DISPLAY INVISIBLE (-6025 4250);
FORCEPROP 1 LAST HDL_TAP TRUE
J 0
(-5700 4175);
DISPLAY 0.574468 (-5700 4175);
PAINT GREEN (-5700 4175);
DISPLAY INVISIBLE (-5700 4175);
FORCEPROP 1 LAST PATH I350
J 0
(-6027 4300);
DISPLAY 0.872340 (-6027 4300);
PAINT GREEN (-6027 4300);
DISPLAY INVISIBLE (-6027 4300);
FORCEADD TAP..6
(-6025 4100);
FORCEPROP 3 LASTPIN (-5975 4100) SIG_NAME P5E_CPU1_P2_RX_DN<15>
J 0
(-5965 4110);
DISPLAY 0.659574 (-5965 4110);
PAINT MONO (-5965 4110);
DISPLAY INVISIBLE (-5965 4110);
FORCEPROP 1 LASTPIN (-5975 4100) BN 15
J 0
(-6027 4108);
DISPLAY 0.489362 (-6027 4108);
PAINT MONO (-6027 4108);
FORCEPROP 2 LAST CDS_LIB standard
J 0
(-6025 4100);
DISPLAY INVISIBLE (-6025 4100);
FORCEPROP 1 LAST BODY_TYPE PLUMBING
J 0
(-6025 4050);
DISPLAY 0.574468 (-6025 4050);
PAINT GREEN (-6025 4050);
DISPLAY INVISIBLE (-6025 4050);
FORCEPROP 1 LAST HDL_TAP TRUE
J 0
(-5700 3975);
DISPLAY 0.574468 (-5700 3975);
PAINT GREEN (-5700 3975);
DISPLAY INVISIBLE (-5700 3975);
FORCEPROP 1 LAST PATH I351
J 0
(-6027 4100);
DISPLAY 0.872340 (-6027 4100);
PAINT GREEN (-6027 4100);
DISPLAY INVISIBLE (-6027 4100);
FORCEADD TAP..6
(-6025 4200);
FORCEPROP 3 LASTPIN (-5975 4200) SIG_NAME P5E_CPU1_P2_RX_DN<14>
J 0
(-5965 4210);
DISPLAY 0.659574 (-5965 4210);
PAINT MONO (-5965 4210);
DISPLAY INVISIBLE (-5965 4210);
FORCEPROP 1 LASTPIN (-5975 4200) BN 14
J 0
(-6027 4208);
DISPLAY 0.489362 (-6027 4208);
PAINT MONO (-6027 4208);
FORCEPROP 2 LAST CDS_LIB standard
J 0
(-6025 4200);
DISPLAY INVISIBLE (-6025 4200);
FORCEPROP 1 LAST BODY_TYPE PLUMBING
J 0
(-6025 4150);
DISPLAY 0.574468 (-6025 4150);
PAINT GREEN (-6025 4150);
DISPLAY INVISIBLE (-6025 4150);
FORCEPROP 1 LAST HDL_TAP TRUE
J 0
(-5700 4075);
DISPLAY 0.574468 (-5700 4075);
PAINT GREEN (-5700 4075);
DISPLAY INVISIBLE (-5700 4075);
FORCEPROP 1 LAST PATH I352
J 0
(-6027 4200);
DISPLAY 0.872340 (-6027 4200);
PAINT GREEN (-6027 4200);
DISPLAY INVISIBLE (-6027 4200);
FORCEADD OFFPAGE..1
(-7075 5875);
FORCEPROP 2 LAST $XR0 340 
J 0
(-7327 5875);
DISPLAY 0.638298 (-7327 5875);
PAINT MONO (-7327 5875);
FORCEPROP 2 LAST CDS_LIB standard
J 0
(-7075 5875);
DISPLAY INVISIBLE (-7075 5875);
FORCEPROP 1 LAST OFFPAGE TRUE
J 0
(-6750 5750);
DISPLAY 0.872340 (-6750 5750);
PAINT GREEN (-6750 5750);
DISPLAY INVISIBLE (-6750 5750);
FORCEPROP 1 LAST COMMENT_BODY TRUE
J 0
(-6950 5775);
DISPLAY 0.872340 (-6950 5775);
PAINT GREEN (-6950 5775);
DISPLAY INVISIBLE (-6950 5775);
FORCEPROP 2 LAST PATH I353
J 0
(-7025 5950);
DISPLAY 1.021277 (-7025 5950);
DISPLAY INVISIBLE (-7025 5950);
FORCEADD OFFPAGE..1
(-7075 5825);
FORCEPROP 2 LAST $XR0 340 
J 0
(-7327 5825);
DISPLAY 0.638298 (-7327 5825);
PAINT MONO (-7327 5825);
FORCEPROP 2 LAST CDS_LIB standard
J 0
(-7075 5825);
DISPLAY INVISIBLE (-7075 5825);
FORCEPROP 1 LAST OFFPAGE TRUE
J 0
(-6750 5700);
DISPLAY 0.872340 (-6750 5700);
PAINT GREEN (-6750 5700);
DISPLAY INVISIBLE (-6750 5700);
FORCEPROP 1 LAST COMMENT_BODY TRUE
J 0
(-6950 5725);
DISPLAY 0.872340 (-6950 5725);
PAINT GREEN (-6950 5725);
DISPLAY INVISIBLE (-6950 5725);
FORCEPROP 2 LAST PATH I354
J 0
(-7025 5900);
DISPLAY 1.021277 (-7025 5900);
DISPLAY INVISIBLE (-7025 5900);
FORCEADD QUANTA_TITLE_BLOCK_C..1
(0 0);
FORCEPROP 0 LAST CDS_CON_LAST_MODIFIED Thu Sep 14 16:11:59 2023
J 0
(-1885 15);
DISPLAY INVISIBLE (-1885 15);
FORCEPROP 1 LAST CUSTOM_TXT_CDS <CON_LAST_MODIFIED>
J 0
(-1885 15);
DISPLAY 0.978723 (-1885 15);
FORCEPROP 2 LAST CUSTOM_TXT_CDS <XR_PAGE_TITLE>
J 0
(-7890 5250);
DISPLAY 0.638298 (-7890 5250);
PAINT PINK (-7890 5250);
DISPLAY INVISIBLE (-7890 5250);
FORCEPROP 1 LAST CUSTOM_TXT_CDS <NAME_2>
J 0
(-3175 50);
FORCEPROP 1 LAST CUSTOM_TXT_CDS <NAME_1>
J 0
(-3175 175);
FORCEPROP 1 LAST CUSTOM_TXT_CDS <Q_NUMBER>
J 0
(-1403 103);
DISPLAY 1.212766 (-1403 103);
FORCEPROP 1 LAST CUSTOM_TXT_CDS <Q_PROJ>
J 0
(-2382 102);
DISPLAY 1.212766 (-2382 102);
FORCEPROP 1 LAST CUSTOM_TXT_CDS <Q_REV>
J 0
(-184 103);
DISPLAY 1.212766 (-184 103);
FORCEPROP 1 LAST CUSTOM_TXT_CDS <CON_PAGE_NUM> OF <CON_TOTAL_PAGES>
J 0
(-446 18);
DISPLAY 0.978723 (-446 18);
FORCEPROP 1 LAST Q_TITLE CPU1 PCIE P2/P3
J 0
(-9366 26);
DISPLAY 2.446809 (-9366 26);
PAINT GREEN (-9366 26);
FORCEPROP 2 LAST CDS_LIB pure_quanta
J 0
(0 0);
DISPLAY INVISIBLE (0 0);
FORCEPROP 1 LAST CDS_LMAN_SYM_OUTLINE -9475,6775,100,-125
J 0
(0 0);
DISPLAY 0.468085 (0 0);
PAINT GREEN (0 0);
DISPLAY INVISIBLE (0 0);
FORCEPROP 2 LAST PAGE_BORDER TRUE
J 0
(-7890 5250);
DISPLAY 0.638298 (-7890 5250);
PAINT PINK (-7890 5250);
DISPLAY INVISIBLE (-7890 5250);
FORCEPROP 2 LAST CDS_XR_PAGE_TITLE CR-52 : @T6G_MB_LIB.T6G(SCH_1):PAGE52
J 0
(-7890 5250);
DISPLAY 0.638298 (-7890 5250);
PAINT PINK (-7890 5250);
DISPLAY INVISIBLE (-7890 5250);
FORCEPROP 1 LAST Q_DEPT BU9
J 1
(-3763 49);
DISPLAY 1.957447 (-3763 49);
PAINT GREEN (-3763 49);
DISPLAY INVISIBLE (-3763 49);
FORCEPROP 1 LAST COMMENT_BODY TRUE
J 0
(12 -13);
DISPLAY 0.978723 (12 -13);
PAINT GREEN (12 -13);
DISPLAY INVISIBLE (12 -13);
WIRE 17 -1 (-6075 1625)(-6075 1725);
WIRE 17 -1 (-6075 1725)(-6075 1825);
WIRE 17 -1 (-6075 1825)(-6075 1925);
WIRE 17 -1 (-6075 1925)(-6075 2025);
WIRE 17 -1 (-6075 2025)(-6075 2125);
WIRE 17 -1 (-6075 2125)(-6075 2225);
WIRE 17 -1 (-6075 2225)(-6075 2325);
WIRE 17 -1 (-6075 2325)(-6075 2425);
WIRE 17 -1 (-6075 2425)(-6075 2525);
WIRE 17 -1 (-6075 2525)(-6075 2625);
WIRE 17 -1 (-6075 2625)(-6075 2725);
WIRE 17 -1 (-6075 2725)(-6075 2825);
WIRE 17 -1 (-6075 2825)(-6075 2925);
WIRE 17 -1 (-6075 2925)(-6075 3025);
WIRE 17 -1 (-6075 3025)(-6075 3125);
WIRE 17 -1 (-6075 3125)(-6075 3325);
WIRE 17 -1 (-7025 3325)(-6075 3325);
FORCEPROP 2 LAST SIG_NAME P5E_CPU1_P3_RX_DN<15:0>
J 0
(-6985 3335);
DISPLAY 0.489362 (-6985 3335);
WIRE 17 -1 (-5925 1675)(-5925 1775);
WIRE 17 -1 (-5925 1775)(-5925 1875);
WIRE 17 -1 (-5925 1875)(-5925 1975);
WIRE 17 -1 (-5925 1975)(-5925 2075);
WIRE 17 -1 (-5925 2075)(-5925 2175);
WIRE 17 -1 (-5925 2175)(-5925 2275);
WIRE 17 -1 (-5925 2275)(-5925 2375);
WIRE 17 -1 (-5925 2375)(-5925 2475);
WIRE 17 -1 (-5925 2475)(-5925 2575);
WIRE 17 -1 (-5925 2575)(-5925 2675);
WIRE 17 -1 (-5925 2675)(-5925 2775);
WIRE 17 -1 (-5925 2775)(-5925 2875);
WIRE 17 -1 (-5925 2875)(-5925 2975);
WIRE 17 -1 (-5925 2975)(-5925 3075);
WIRE 17 -1 (-5925 3075)(-5925 3175);
WIRE 17 -1 (-5925 3175)(-5925 3375);
WIRE 17 -1 (-5925 3375)(-7025 3375);
FORCEPROP 2 LAST SIG_NAME P5E_CPU1_P3_RX_DP<15:0>
J 0
(-6985 3385);
DISPLAY 0.489362 (-6985 3385);
WIRE 17 -1 (-3250 1725)(-3250 1625);
WIRE 17 -1 (-3250 1825)(-3250 1725);
WIRE 17 -1 (-3250 1925)(-3250 1825);
WIRE 17 -1 (-3250 2025)(-3250 1925);
WIRE 17 -1 (-3250 2125)(-3250 2025);
WIRE 17 -1 (-3250 2225)(-3250 2125);
WIRE 17 -1 (-3250 2325)(-3250 2225);
WIRE 17 -1 (-3250 2425)(-3250 2325);
WIRE 17 -1 (-3250 2525)(-3250 2425);
WIRE 17 -1 (-3250 2625)(-3250 2525);
WIRE 17 -1 (-3250 2725)(-3250 2625);
WIRE 17 -1 (-3250 2825)(-3250 2725);
WIRE 17 -1 (-3250 2925)(-3250 2825);
WIRE 17 -1 (-3250 3025)(-3250 2925);
WIRE 17 -1 (-3250 3125)(-3250 3025);
WIRE 17 -1 (-3250 3325)(-3250 3125);
WIRE 17 -1 (-3250 3325)(-2375 3325);
FORCEPROP 2 LAST SIG_NAME P5E_CPU1_P3_TX_DN<15:0>
J 0
(-3210 3335);
DISPLAY 0.489362 (-3210 3335);
WIRE 17 -1 (-3400 1775)(-3400 1675);
WIRE 17 -1 (-3400 1875)(-3400 1775);
WIRE 17 -1 (-3400 1975)(-3400 1875);
WIRE 17 -1 (-3400 2075)(-3400 1975);
WIRE 17 -1 (-3400 2175)(-3400 2075);
WIRE 17 -1 (-3400 2275)(-3400 2175);
WIRE 17 -1 (-3400 2375)(-3400 2275);
WIRE 17 -1 (-3400 2475)(-3400 2375);
WIRE 17 -1 (-3400 2575)(-3400 2475);
WIRE 17 -1 (-3400 2675)(-3400 2575);
WIRE 17 -1 (-3400 2775)(-3400 2675);
WIRE 17 -1 (-3400 2875)(-3400 2775);
WIRE 17 -1 (-3400 2975)(-3400 2875);
WIRE 17 -1 (-3400 3075)(-3400 2975);
WIRE 17 -1 (-3400 3175)(-3400 3075);
WIRE 17 -1 (-3400 3375)(-3400 3175);
WIRE 17 -1 (-3400 3375)(-2375 3375);
FORCEPROP 2 LAST SIG_NAME P5E_CPU1_P3_TX_DP<15:0>
J 0
(-3210 3385);
DISPLAY 0.489362 (-3210 3385);
WIRE 17 -1 (-3250 5025)(-3250 4925);
WIRE 17 -1 (-3250 5125)(-3250 5025);
WIRE 17 -1 (-3250 4925)(-3250 4825);
WIRE 17 -1 (-3250 4825)(-3250 4725);
WIRE 17 -1 (-3250 5225)(-3250 5125);
WIRE 17 -1 (-3250 5325)(-3250 5225);
WIRE 17 -1 (-3250 4725)(-3250 4625);
WIRE 17 -1 (-3250 4625)(-3250 4525);
WIRE 17 -1 (-3250 5425)(-3250 5325);
WIRE 17 -1 (-3250 5525)(-3250 5425);
WIRE 17 -1 (-3250 4525)(-3250 4425);
WIRE 17 -1 (-3250 4425)(-3250 4325);
WIRE 17 -1 (-3250 5625)(-3250 5525);
WIRE 17 -1 (-3250 5825)(-3250 5625);
WIRE 17 -1 (-3250 4325)(-3250 4225);
WIRE 17 -1 (-3250 4225)(-3250 4125);
WIRE 17 -1 (-3250 5825)(-2375 5825);
FORCEPROP 2 LAST SIG_NAME P5E_CPU1_P2_TX_DN<15:0>
J 0
(-3185 5835);
DISPLAY 0.489362 (-3185 5835);
WIRE 17 -1 (-3400 5075)(-3400 4975);
WIRE 17 -1 (-3400 5175)(-3400 5075);
WIRE 17 -1 (-3400 4975)(-3400 4875);
WIRE 17 -1 (-3400 4875)(-3400 4775);
WIRE 17 -1 (-3400 5275)(-3400 5175);
WIRE 17 -1 (-3400 5375)(-3400 5275);
WIRE 17 -1 (-3400 4775)(-3400 4675);
WIRE 17 -1 (-3400 4675)(-3400 4575);
WIRE 17 -1 (-3400 5475)(-3400 5375);
WIRE 17 -1 (-3400 5575)(-3400 5475);
WIRE 17 -1 (-3400 4575)(-3400 4475);
WIRE 17 -1 (-3400 4475)(-3400 4375);
WIRE 17 -1 (-3400 5675)(-3400 5575);
WIRE 17 -1 (-3400 5875)(-3400 5675);
WIRE 17 -1 (-3400 4375)(-3400 4275);
WIRE 17 -1 (-3400 4275)(-3400 4175);
WIRE 17 -1 (-3400 5875)(-2375 5875);
FORCEPROP 2 LAST SIG_NAME P5E_CPU1_P2_TX_DP<15:0>
J 0
(-3185 5885);
DISPLAY 0.489362 (-3185 5885);
WIRE 17 -1 (-5925 5575)(-5925 5675);
WIRE 17 -1 (-5925 5475)(-5925 5575);
WIRE 17 -1 (-5925 5675)(-5925 5875);
WIRE 17 -1 (-5925 5875)(-7025 5875);
FORCEPROP 2 LAST SIG_NAME P5E_CPU1_P2_RX_DP<15:0>
J 0
(-6960 5885);
DISPLAY 0.489362 (-6960 5885);
WIRE 17 -1 (-5925 5375)(-5925 5475);
WIRE 17 -1 (-5925 5275)(-5925 5375);
WIRE 17 -1 (-5925 5175)(-5925 5275);
WIRE 17 -1 (-5925 5075)(-5925 5175);
WIRE 17 -1 (-5925 4975)(-5925 5075);
WIRE 17 -1 (-5925 4875)(-5925 4975);
WIRE 17 -1 (-5925 4775)(-5925 4875);
WIRE 17 -1 (-5925 4675)(-5925 4775);
WIRE 17 -1 (-5925 4575)(-5925 4675);
WIRE 17 -1 (-5925 4475)(-5925 4575);
WIRE 17 -1 (-5925 4375)(-5925 4475);
WIRE 17 -1 (-5925 4275)(-5925 4375);
WIRE 17 -1 (-5925 4175)(-5925 4275);
WIRE 17 -1 (-6075 5525)(-6075 5625);
WIRE 17 -1 (-6075 5425)(-6075 5525);
WIRE 17 -1 (-6075 5625)(-6075 5825);
WIRE 17 -1 (-6075 5825)(-7025 5825);
FORCEPROP 2 LAST SIG_NAME P5E_CPU1_P2_RX_DN<15:0>
J 0
(-6960 5835);
DISPLAY 0.489362 (-6960 5835);
WIRE 17 -1 (-6075 5325)(-6075 5425);
WIRE 17 -1 (-6075 5225)(-6075 5325);
WIRE 17 -1 (-6075 5125)(-6075 5225);
WIRE 17 -1 (-6075 5025)(-6075 5125);
WIRE 17 -1 (-6075 4925)(-6075 5025);
WIRE 17 -1 (-6075 4825)(-6075 4925);
WIRE 17 -1 (-6075 4725)(-6075 4825);
WIRE 17 -1 (-6075 4625)(-6075 4725);
WIRE 17 -1 (-6075 4525)(-6075 4625);
WIRE 17 -1 (-6075 4425)(-6075 4525);
WIRE 17 -1 (-6075 4325)(-6075 4425);
WIRE 17 -1 (-6075 4225)(-6075 4325);
WIRE 17 -1 (-6075 4125)(-6075 4225);
WIRE 16 -1 (-3875 3000)(-3350 3000);
WIRE 16 -1 (-3875 2800)(-3350 2800);
WIRE 16 -1 (-5975 4100)(-5375 4100);
WIRE 16 -1 (-5975 4300)(-5375 4300);
WIRE 16 -1 (-5825 4250)(-5375 4250);
WIRE 16 -1 (-5975 4200)(-5375 4200);
WIRE 16 -1 (-5825 4150)(-5375 4150);
WIRE 16 -1 (-5825 3150)(-5375 3150);
WIRE 16 -1 (-5825 3050)(-5375 3050);
WIRE 16 -1 (-5825 2950)(-5375 2950);
WIRE 16 -1 (-5975 2900)(-5375 2900);
WIRE 16 -1 (-5825 2850)(-5375 2850);
WIRE 16 -1 (-5975 3000)(-5375 3000);
WIRE 16 -1 (-5975 3100)(-5375 3100);
WIRE 16 -1 (-3875 2600)(-3350 2600);
WIRE 16 -1 (-3875 2550)(-3500 2550);
WIRE 16 -1 (-3875 2500)(-3350 2500);
WIRE 16 -1 (-3875 3150)(-3500 3150);
WIRE 16 -1 (-3875 3100)(-3350 3100);
WIRE 16 -1 (-3875 3050)(-3500 3050);
WIRE 16 -1 (-3875 2700)(-3350 2700);
WIRE 16 -1 (-3875 2650)(-3500 2650);
WIRE 16 -1 (-3875 2450)(-3500 2450);
WIRE 16 -1 (-3875 4150)(-3500 4150);
WIRE 16 -1 (-3875 4100)(-3350 4100);
WIRE 16 -1 (-3875 5400)(-3350 5400);
WIRE 16 -1 (-3875 5450)(-3500 5450);
WIRE 16 -1 (-3875 5500)(-3350 5500);
WIRE 16 -1 (-3875 5550)(-3500 5550);
WIRE 16 -1 (-3875 5600)(-3350 5600);
WIRE 16 -1 (-3875 5650)(-3500 5650);
WIRE 16 -1 (-5975 5600)(-5375 5600);
WIRE 16 -1 (-5975 4400)(-5375 4400);
WIRE 16 -1 (-5975 4500)(-5375 4500);
WIRE 16 -1 (-5975 4600)(-5375 4600);
WIRE 16 -1 (-5975 4700)(-5375 4700);
WIRE 16 -1 (-5975 4800)(-5375 4800);
WIRE 16 -1 (-5975 4900)(-5375 4900);
WIRE 16 -1 (-5975 5000)(-5375 5000);
WIRE 16 -1 (-5975 5100)(-5375 5100);
WIRE 16 -1 (-5975 5200)(-5375 5200);
WIRE 16 -1 (-5975 5300)(-5375 5300);
WIRE 16 -1 (-5975 5400)(-5375 5400);
WIRE 16 -1 (-5975 5500)(-5375 5500);
WIRE 16 -1 (-5825 4350)(-5375 4350);
WIRE 16 -1 (-5825 4450)(-5375 4450);
WIRE 16 -1 (-5825 4550)(-5375 4550);
WIRE 16 -1 (-5825 4650)(-5375 4650);
WIRE 16 -1 (-5825 4750)(-5375 4750);
WIRE 16 -1 (-5825 4850)(-5375 4850);
WIRE 16 -1 (-5825 4950)(-5375 4950);
WIRE 16 -1 (-5825 5050)(-5375 5050);
WIRE 16 -1 (-5825 5150)(-5375 5150);
WIRE 16 -1 (-5825 5250)(-5375 5250);
WIRE 16 -1 (-5825 5350)(-5375 5350);
WIRE 16 -1 (-5825 5450)(-5375 5450);
WIRE 16 -1 (-5825 5550)(-5375 5550);
WIRE 16 -1 (-5825 5650)(-5375 5650);
WIRE 16 -1 (-3875 5350)(-3500 5350);
WIRE 16 -1 (-3875 5300)(-3350 5300);
WIRE 16 -1 (-3875 4700)(-3350 4700);
WIRE 16 -1 (-3875 4550)(-3500 4550);
WIRE 16 -1 (-3875 4600)(-3350 4600);
WIRE 16 -1 (-3875 5250)(-3500 5250);
WIRE 16 -1 (-3875 5150)(-3500 5150);
WIRE 16 -1 (-3875 5200)(-3350 5200);
WIRE 16 -1 (-3875 4850)(-3500 4850);
WIRE 16 -1 (-3875 4800)(-3350 4800);
WIRE 16 -1 (-3875 4750)(-3500 4750);
WIRE 16 -1 (-3875 4650)(-3500 4650);
WIRE 16 -1 (-3875 4500)(-3350 4500);
WIRE 16 -1 (-3875 4450)(-3500 4450);
WIRE 16 -1 (-3875 4400)(-3350 4400);
WIRE 16 -1 (-3875 4350)(-3500 4350);
WIRE 16 -1 (-3875 4300)(-3350 4300);
WIRE 16 -1 (-3875 4250)(-3500 4250);
WIRE 16 -1 (-3875 4200)(-3350 4200);
WIRE 16 -1 (-3875 5050)(-3500 5050);
WIRE 16 -1 (-3875 4950)(-3500 4950);
WIRE 16 -1 (-3875 5100)(-3350 5100);
WIRE 16 -1 (-3875 5000)(-3350 5000);
WIRE 16 -1 (-3875 4900)(-3350 4900);
WIRE 16 -1 (-3875 2950)(-3500 2950);
WIRE 16 -1 (-3875 2900)(-3350 2900);
WIRE 16 -1 (-3875 2850)(-3500 2850);
WIRE 16 -1 (-3875 2750)(-3500 2750);
WIRE 16 -1 (-3875 2400)(-3350 2400);
WIRE 16 -1 (-3875 2350)(-3500 2350);
WIRE 16 -1 (-3875 2300)(-3350 2300);
WIRE 16 -1 (-3875 2250)(-3500 2250);
WIRE 16 -1 (-3875 2200)(-3350 2200);
WIRE 16 -1 (-3875 2150)(-3500 2150);
WIRE 16 -1 (-3875 2100)(-3350 2100);
WIRE 16 -1 (-3875 2050)(-3500 2050);
WIRE 16 -1 (-3875 2000)(-3350 2000);
WIRE 16 -1 (-3875 1950)(-3500 1950);
WIRE 16 -1 (-3875 1900)(-3350 1900);
WIRE 16 -1 (-3875 1850)(-3500 1850);
WIRE 16 -1 (-3875 1800)(-3350 1800);
WIRE 16 -1 (-3875 1750)(-3500 1750);
WIRE 16 -1 (-3875 1700)(-3350 1700);
WIRE 16 -1 (-3875 1650)(-3500 1650);
WIRE 16 -1 (-3875 1600)(-3350 1600);
WIRE 16 -1 (-5975 2800)(-5375 2800);
WIRE 16 -1 (-5825 2750)(-5375 2750);
WIRE 16 -1 (-5975 2700)(-5375 2700);
WIRE 16 -1 (-5825 2650)(-5375 2650);
WIRE 16 -1 (-5975 2600)(-5375 2600);
WIRE 16 -1 (-5825 2550)(-5375 2550);
WIRE 16 -1 (-5975 2500)(-5375 2500);
WIRE 16 -1 (-5825 2450)(-5375 2450);
WIRE 16 -1 (-5975 2400)(-5375 2400);
WIRE 16 -1 (-5825 2350)(-5375 2350);
WIRE 16 -1 (-5975 2300)(-5375 2300);
WIRE 16 -1 (-5825 2250)(-5375 2250);
WIRE 16 -1 (-5975 2200)(-5375 2200);
WIRE 16 -1 (-5825 2150)(-5375 2150);
WIRE 16 -1 (-5975 2100)(-5375 2100);
WIRE 16 -1 (-5825 2050)(-5375 2050);
WIRE 16 -1 (-5975 2000)(-5375 2000);
WIRE 16 -1 (-5825 1950)(-5375 1950);
WIRE 16 -1 (-5975 1900)(-5375 1900);
WIRE 16 -1 (-5825 1850)(-5375 1850);
WIRE 16 -1 (-5975 1800)(-5375 1800);
WIRE 16 -1 (-5825 1750)(-5375 1750);
WIRE 16 -1 (-5975 1700)(-5375 1700);
WIRE 16 -1 (-5825 1650)(-5375 1650);
WIRE 16 -1 (-5975 1600)(-5375 1600);
FORCENOTE
CPU1 P3[15:0] TO EXAMAX
(-2575 2675) 0;
DISPLAY LEFT (-2575 2675);
DISPLAY 2.000000 (-2575 2675);
FORCENOTE
CPU1 P2[15:0] TO EXAMAX
(-2475 4775) 0;
DISPLAY LEFT (-2475 4775);
DISPLAY 2.000000 (-2475 4775);
QUIT
